G04 ================== begin FILE IDENTIFICATION RECORD ==================*
G04 Layout Name:  D:/<user>/Wistron_project/16315-1/gbr/16315-1.brd*
G04 Film Name:    L10*
G04 File Format:  Gerber RS274X*
G04 File Origin:  Cadence Allegro 16.5-S056*
G04 Origin Date:  Fri Jun 09 15:32:05 2017*
G04 *
G04 Layer:  VIA CLASS/L10*
G04 Layer:  PIN/L10*
G04 Layer:  ETCH/L10*
G04 Layer:  DRAWING FORMAT/LAYER_PCB_STORY*
G04 Layer:  DRAWING FORMAT/LAYER_L10*
G04 *
G04 Offset:    (0.00 0.00)*
G04 Mirror:    No*
G04 Mode:      Positive*
G04 Rotation:  0*
G04 FullContactRelief:  No*
G04 UndefLineWidth:     6.00*
G04 ================== end FILE IDENTIFICATION RECORD ====================*
%FSLAX35Y35*MOIN*%
%IR0*IPPOS*OFA0.00000B0.00000*MIA0B0*SFA1.00000B1.00000*%
%ADD16C,.02*%
%ADD12C,.03*%
%ADD11C,.022*%
%ADD13C,.042*%
%ADD14C,.034*%
%ADD10C,.028*%
%ADD15C,.048*%
%ADD17C,.01*%
%ADD18C,.006*%
%ADD19C,.008*%
%ADD20C,.0055*%
%ADD21C,.00425*%
%ADD22C,.00525*%
%ADD23C,.04604*%
G75*
%LPD*%
G75*
G36*
G01X3937Y3004D02*
G02X3004Y3937I0J933D01*
G01Y12071D01*
G02X3714Y12323I400J0D01*
G03X7898Y8796I11444J9330D01*
G01X8000Y8739D01*
Y8000D01*
X9537D01*
X9574Y7985D01*
G03X20778Y8000I5584J13669D01*
G01X393575D01*
Y55118D01*
G02X405512Y67055I11937J0D01*
G01X408351D01*
Y62059D01*
X405512D01*
G03X398571Y55118I0J-6941D01*
G01Y3937D01*
G02X397638Y3004I-933J0D01*
G01X3937D01*
G37*
G36*
G01X8000Y34568D02*
G03X3714Y30984I7158J-12914D01*
G02X3004Y31236I-310J253D01*
G01Y461899D01*
G02X3678Y462191I400J0D01*
G03X8000Y459248I11482J12217D01*
G01Y34568D01*
G37*
G36*
G01X758787Y1460504D02*
Y1378740D01*
G02X746850Y1366803I-11937J0D01*
G01X8000D01*
Y489570D01*
G03X3678Y486627I7160J-15160D01*
G02X3004Y486919I-274J292D01*
G01Y1370866D01*
G02X3937Y1371799I933J0D01*
G01X746850D01*
G03X753791Y1378740I0J6941D01*
G01Y1464567D01*
G02X754724Y1465500I933J0D01*
G01X783465D01*
G03X790406Y1472441I0J6941D01*
G01Y1654331D01*
G02X791339Y1655264I933J0D01*
G01X799262D01*
Y1650268D01*
X795402D01*
Y1472441D01*
G02X795364Y1471483I-11937J-6D01*
G03X794795Y1468683I1484J-1759D01*
G02X783465Y1460504I-11330J3758D01*
G01X758787D01*
G37*
G36*
G01X598551Y8000D02*
X783465D01*
G02X794689Y126I0J-11937D01*
G01X796727D01*
Y-4870D01*
X791339D01*
G02X790406Y-3937I0J933D01*
G03X783465Y3004I-6941J0D01*
G01X594488D01*
G02X593555Y3937I0J933D01*
G01Y55118D01*
G03X586614Y62059I-6941J0D01*
G01X585511D01*
Y67055D01*
X586614D01*
G02X598551Y55118I0J-11937D01*
G01Y8000D01*
G37*
G36*
G01X634958Y532762D02*
X651530Y549334D01*
Y571435D01*
X653777Y573682D01*
X660152D01*
X661036Y572798D01*
Y560629D01*
X661034Y560626D01*
Y547121D01*
X639527Y525614D01*
X605483D01*
X599883Y520014D01*
Y511761D01*
X598855Y510733D01*
X589963D01*
X589267Y511429D01*
Y523031D01*
X598998Y532762D01*
X634958D01*
G37*
G36*
G01X1367075Y3937D02*
G02X1366142Y3004I-933J0D01*
G01X1185039D01*
G03X1178098Y-3937I0J-6941D01*
G01Y-148819D01*
G02X1177165Y-149752I-933J0D01*
G01X870079D01*
G02X869146Y-148819I0J933D01*
G01Y-16366D01*
X874142D01*
Y-144756D01*
X1173102D01*
Y-3937D01*
G02X1185039Y8000I11937J0D01*
G01X1362079D01*
Y55118D01*
G02X1374016Y67055I11937J0D01*
G01X1376944D01*
Y62059D01*
X1374016D01*
G03X1367075Y55118I0J-6941D01*
G01Y3937D01*
G37*
G36*
G01X1029788Y-72550D02*
X1027423Y-70185D01*
Y-35639D01*
X1030030Y-33032D01*
X1030437D01*
Y-33312D01*
X1030382Y-33370D01*
G03X1033956Y-33657I1671J-1583D01*
G02X1034286Y-33032I330J225D01*
G01X1036389D01*
G02X1036733Y-33636I0J-400D01*
G03X1040691I1979J-1176D01*
G02X1041035Y-33032I344J204D01*
G01X1045416D01*
X1048419Y-36035D01*
Y-70791D01*
X1046660Y-72550D01*
X1029788D01*
G37*
G36*
G01X1003681Y1450890D02*
X994483Y1460088D01*
Y1484623D01*
X995360Y1485500D01*
X1080220D01*
X1082000Y1487280D01*
Y1609593D01*
X1086719Y1614312D01*
X1137982D01*
X1145983Y1606311D01*
Y1459747D01*
X1137126Y1450890D01*
X1003681D01*
G37*
G36*
G01X1080573Y1488483D02*
X1079590Y1487500D01*
X995961D01*
X994302Y1489159D01*
Y1534567D01*
X995775Y1536040D01*
X1078460D01*
X1080573Y1533927D01*
Y1488483D01*
G37*
G36*
G01X1054856Y-76484D02*
X1052614Y-74242D01*
Y-42447D01*
G02X1053252Y-42126I400J0D01*
G03X1052959Y-38690I1373J1848D01*
G01X1052900Y-38752D01*
X1052614D01*
Y-38377D01*
X1055365Y-35626D01*
X1068000D01*
X1071362Y-38988D01*
Y-65238D01*
G02X1070894Y-65632I-400J0D01*
G03Y-70168I-394J-2268D01*
G02X1071362Y-70562I68J-394D01*
G01Y-70916D01*
G02X1070956Y-71316I-400J0D01*
G03X1070012Y-75734I-38J-2302D01*
G02X1070137Y-76385I-157J-368D01*
G01X1070038Y-76484D01*
X1054856D01*
G37*
G36*
G01X1567055Y55118D02*
Y8000D01*
X1889065D01*
G03X1900305I5620J13654D01*
G01X1926843D01*
Y1366803D01*
X1168110D01*
G02X1156173Y1378740I0J11937D01*
G01Y1468504D01*
G02X1168110Y1480441I11937J0D01*
G01X1212472D01*
Y1650268D01*
X1071589D01*
Y1655264D01*
X1216535D01*
G02X1217468Y1654331I0J-933D01*
G01Y1476378D01*
G02X1216535Y1475445I-933J0D01*
G01X1168110D01*
G03X1161169Y1468504I0J-6941D01*
G01Y1378740D01*
G03X1168110Y1371799I6941J0D01*
G01X1930906D01*
G02X1931839Y1370866I0J-933D01*
G01Y3937D01*
G02X1930906Y3004I-933J0D01*
G01X1562992D01*
G02X1562059Y3937I0J933D01*
G01Y55118D01*
G03X1555118Y62059I-6941J0D01*
G01X1554061D01*
Y67055D01*
X1555118D01*
G02X1567055Y55118I0J-11937D01*
G37*
G36*
G01X1436900Y584833D02*
X1409800Y557733D01*
Y547400D01*
X1408900Y546500D01*
X1403400D01*
X1402700Y547200D01*
Y560769D01*
X1434332Y592401D01*
X1435945D01*
X1436900Y591446D01*
Y584833D01*
G37*
%LPC*%
G75*
G36*
G01X1123366Y1586608D02*
G03X1122697I-334J-220D01*
G02Y1590558I-3012J1975D01*
G03X1123366I335J220D01*
G02Y1586608I3012J-1975D01*
G37*
G36*
G01X1105138D02*
G03X1104469I-334J-220D01*
G02Y1590558I-3012J1975D01*
G03X1105138I334J220D01*
G02Y1586608I3012J-1975D01*
G37*
G36*
G01X1095005Y1553378D02*
G03X1094469I-268J-297D01*
G02X1091290Y1556706I-1543J1708D01*
G03Y1557268I-284J281D01*
G02X1094469Y1560596I1636J1620D01*
G03X1095005I268J297D01*
G02X1098184Y1557268I1543J-1708D01*
G03Y1556706I284J-281D01*
G02X1095005Y1553378I-1636J-1620D01*
G37*
G36*
G01X1097575Y1533801D02*
G03Y1533239I284J-281D01*
G02X1094301I-1637J-1619D01*
G03Y1533801I-284J281D01*
G02X1097575I1637J1619D01*
G37*
G36*
G01X1092455D02*
G03Y1533239I284J-281D01*
G02X1089181I-1637J-1619D01*
G03Y1533801I-284J281D01*
G02X1092455I1637J1619D01*
G37*
G36*
G01X1075050Y1453527D02*
G03X1074458I-296J-269D01*
G02Y1456623I-1704J1548D01*
G03X1075050I296J269D01*
G02Y1453527I1704J-1548D01*
G37*
G36*
G01X1046358Y1456623D02*
G03X1046950I296J269D01*
G02Y1453527I1704J-1548D01*
G03X1046358I-296J-269D01*
G02Y1456623I-1704J1548D01*
G37*
G36*
G01X1018558D02*
G03X1019150I296J269D01*
G02Y1453527I1704J-1548D01*
G03X1018558I-296J-269D01*
G02Y1456623I-1704J1548D01*
G37*
G54D23*
X1035000Y-66800D03*
X1058333Y-72770D03*
X1061325Y-40378D03*
%LPD*%
G75*
G54D10*
X24508Y5500D03*
X5500Y61492D03*
Y56492D03*
Y51492D03*
Y46492D03*
Y41492D03*
Y66492D03*
Y81492D03*
Y76492D03*
Y96492D03*
Y91492D03*
Y86492D03*
Y71492D03*
Y101492D03*
Y111492D03*
Y116492D03*
Y106492D03*
Y126492D03*
Y121492D03*
Y141492D03*
Y151492D03*
Y161492D03*
Y156492D03*
Y146492D03*
Y131492D03*
Y136492D03*
Y181492D03*
Y191492D03*
Y201492D03*
Y211492D03*
Y171492D03*
Y206492D03*
Y196492D03*
Y176492D03*
Y166492D03*
Y186492D03*
Y231492D03*
Y241492D03*
Y251492D03*
Y261492D03*
Y221492D03*
Y256492D03*
Y246492D03*
Y226492D03*
Y216492D03*
Y236492D03*
Y281492D03*
Y291492D03*
Y301492D03*
Y271492D03*
Y306492D03*
Y296492D03*
Y286492D03*
Y276492D03*
Y266492D03*
Y331492D03*
Y341492D03*
Y351492D03*
Y311492D03*
Y321492D03*
Y356492D03*
Y346492D03*
Y336492D03*
Y326492D03*
Y316492D03*
Y381492D03*
Y391492D03*
Y401492D03*
Y361492D03*
Y371492D03*
Y406492D03*
Y396492D03*
Y386492D03*
Y376492D03*
Y366492D03*
Y451492D03*
Y441492D03*
Y431492D03*
Y421492D03*
Y411492D03*
Y416492D03*
Y436492D03*
Y446492D03*
Y426492D03*
Y501492D03*
Y456492D03*
Y496492D03*
Y531492D03*
Y551492D03*
Y541492D03*
Y521492D03*
Y511492D03*
Y536492D03*
Y546492D03*
Y506492D03*
Y516492D03*
Y526492D03*
Y581492D03*
Y591492D03*
Y571492D03*
Y561492D03*
Y586492D03*
Y596492D03*
Y556492D03*
Y566492D03*
Y576492D03*
Y631492D03*
Y641492D03*
Y621492D03*
Y611492D03*
Y601492D03*
Y636492D03*
Y646492D03*
Y606492D03*
Y616492D03*
Y626492D03*
Y681492D03*
Y691492D03*
Y671492D03*
Y661492D03*
Y651492D03*
Y686492D03*
Y696492D03*
Y656492D03*
Y666492D03*
Y676492D03*
Y731492D03*
Y741492D03*
Y721492D03*
Y711492D03*
Y701492D03*
Y736492D03*
Y706492D03*
Y716492D03*
Y726492D03*
Y781492D03*
Y791492D03*
Y771492D03*
Y761492D03*
Y751492D03*
Y786492D03*
Y746492D03*
Y756492D03*
Y766492D03*
Y776492D03*
Y831492D03*
Y841492D03*
Y821492D03*
Y811492D03*
Y801492D03*
Y836492D03*
Y796492D03*
Y806492D03*
Y816492D03*
Y826492D03*
Y881492D03*
Y871492D03*
Y861492D03*
Y851492D03*
Y886492D03*
Y846492D03*
Y856492D03*
Y866492D03*
Y876492D03*
Y931492D03*
Y921492D03*
Y911492D03*
Y901492D03*
Y891492D03*
Y936492D03*
Y896492D03*
Y906492D03*
Y916492D03*
Y926492D03*
Y976492D03*
Y981492D03*
Y986492D03*
Y966492D03*
Y956492D03*
Y961492D03*
Y971492D03*
Y951492D03*
Y941492D03*
Y946492D03*
Y991492D03*
Y996492D03*
Y1001492D03*
Y1006492D03*
Y1026492D03*
Y1016492D03*
Y1011492D03*
Y1021492D03*
Y1031492D03*
Y1036492D03*
Y1066492D03*
Y1056492D03*
Y1046492D03*
Y1041492D03*
Y1051492D03*
Y1061492D03*
Y1071492D03*
Y1081492D03*
Y1076492D03*
Y1121492D03*
Y1131492D03*
Y1111492D03*
Y1101492D03*
Y1091492D03*
Y1086492D03*
Y1096492D03*
Y1106492D03*
Y1116492D03*
Y1126492D03*
Y1171492D03*
Y1161492D03*
Y1151492D03*
Y1141492D03*
Y1136492D03*
Y1146492D03*
Y1156492D03*
Y1166492D03*
Y1176492D03*
Y1221492D03*
Y1211492D03*
Y1201492D03*
Y1191492D03*
Y1181492D03*
Y1186492D03*
Y1196492D03*
Y1206492D03*
Y1216492D03*
Y1226492D03*
Y1271492D03*
Y1261492D03*
Y1251492D03*
Y1241492D03*
Y1231492D03*
Y1236492D03*
Y1246492D03*
Y1256492D03*
Y1266492D03*
Y1276492D03*
Y1321492D03*
Y1311492D03*
Y1301492D03*
Y1291492D03*
Y1281492D03*
Y1286492D03*
Y1296492D03*
Y1306492D03*
Y1316492D03*
X8983Y1368303D03*
X13983D03*
X18983D03*
X23983D03*
X5500Y1361492D03*
Y1351492D03*
Y1341492D03*
Y1331492D03*
Y1336492D03*
Y1346492D03*
Y1356492D03*
Y1326492D03*
X29508Y5500D03*
X39508D03*
X34508D03*
X44508D03*
X64508D03*
X69508D03*
X54508D03*
X49508D03*
X59508D03*
X28983Y1368303D03*
X33983D03*
X38983D03*
X43983D03*
X48983D03*
X53983D03*
X58983D03*
X63983D03*
X68983D03*
X114508Y5500D03*
X119508D03*
X104508D03*
X94508D03*
X84508D03*
X74508D03*
X79508D03*
X89508D03*
X99508D03*
X109508D03*
X73983Y1368303D03*
X78983D03*
X83983D03*
X88983D03*
X93983D03*
X98983D03*
X107374Y1369303D03*
X112374D03*
X117374D03*
X134508Y5500D03*
X124508D03*
X129508D03*
X169508D03*
X159508D03*
X149508D03*
X139508D03*
X154508D03*
X164508D03*
X144508D03*
X122374Y1369303D03*
X127374D03*
X132374D03*
X137374D03*
X142374D03*
X147374D03*
X152374D03*
X157374D03*
X162374D03*
X167374D03*
X209508Y5500D03*
X199508D03*
X189508D03*
X179508D03*
X204508D03*
X214508D03*
X174508D03*
X184508D03*
X194508D03*
X172374Y1369303D03*
X177374D03*
X182374D03*
X187374D03*
X192374D03*
X197374D03*
X202374D03*
X207374D03*
X212374D03*
X217374D03*
X259508Y5500D03*
X249508D03*
X239508D03*
X229508D03*
X219508D03*
X224508D03*
X234508D03*
X244508D03*
X254508D03*
X264508D03*
X222374Y1369303D03*
X227374D03*
X232374D03*
X237374D03*
X242374D03*
X247374D03*
X252374D03*
X257374D03*
X262374D03*
X309508Y5500D03*
X299508D03*
X289508D03*
X279508D03*
X269508D03*
X304508D03*
X314508D03*
X274508D03*
X284508D03*
X294508D03*
X267374Y1369303D03*
X272374D03*
X277374D03*
X282374D03*
X287374D03*
X292374D03*
X297374D03*
X302374D03*
X307374D03*
X312374D03*
X359508Y5500D03*
X349508D03*
X339508D03*
X329508D03*
X319508D03*
X324508D03*
X334508D03*
X344508D03*
X354508D03*
X333983Y1368303D03*
X338983D03*
X343983D03*
X348983D03*
X353983D03*
X358983D03*
X363983D03*
X317374Y1369303D03*
X322374D03*
X327374D03*
X395075Y18639D03*
Y13639D03*
X389508Y5500D03*
X379508D03*
X369508D03*
X364508D03*
X374508D03*
X384508D03*
X394508D03*
X395075Y43639D03*
Y38639D03*
Y33639D03*
Y28639D03*
Y23639D03*
X399000Y62000D03*
X396000Y55500D03*
X396075Y50248D03*
X368983Y1368303D03*
X373983D03*
X378983D03*
X383983D03*
X388983D03*
X393983D03*
X398983D03*
X403983D03*
X408983D03*
X413983D03*
X418983D03*
X423983D03*
X428983D03*
X433983D03*
X438983D03*
X443983D03*
X448983D03*
X453983D03*
X458983D03*
X463983D03*
X468983D03*
X473983D03*
X478983D03*
X483983D03*
X488983D03*
X493983D03*
X498983D03*
X503983D03*
X508983D03*
X517374Y1369303D03*
X522374D03*
X527374D03*
X532374D03*
X537374D03*
X542374D03*
X547374D03*
X552374D03*
X557374D03*
X597051Y7699D03*
Y12699D03*
Y17699D03*
X604146Y5500D03*
X597051Y22699D03*
Y27699D03*
Y32699D03*
Y37699D03*
Y42699D03*
X589000Y64000D03*
X594000Y61500D03*
X596000Y56500D03*
X596051Y51090D03*
X567374Y1369303D03*
X572374D03*
X577374D03*
X582374D03*
X587374D03*
X592374D03*
X597374D03*
X602374D03*
X562374D03*
X609146Y5500D03*
X619146D03*
X614146D03*
X629146D03*
X639146D03*
X649146D03*
X654146D03*
X644146D03*
X634146D03*
X624146D03*
X617374Y1369303D03*
X622374D03*
X627374D03*
X632374D03*
X637374D03*
X642374D03*
X647374D03*
X652374D03*
X607374D03*
X612374D03*
X679146Y5500D03*
X689146D03*
X694146D03*
X684146D03*
X659146D03*
X669146D03*
X664146D03*
X674146D03*
X699146D03*
X667374Y1369303D03*
X672374D03*
X677374D03*
X682374D03*
X687374D03*
X692374D03*
X697374D03*
X702374D03*
X657374D03*
X662374D03*
X749146Y5500D03*
X709146D03*
X719146D03*
X729146D03*
X739146D03*
X744146D03*
X734146D03*
X724146D03*
X714146D03*
X704146D03*
X747374Y1369303D03*
X742374D03*
X717374D03*
X722374D03*
X727374D03*
X732374D03*
X737374D03*
X707374D03*
X712374D03*
X795969Y-1374D03*
X759146Y5500D03*
X769146D03*
X774146D03*
X764146D03*
X754146D03*
X779146D03*
X755500Y1374500D03*
X752500Y1370500D03*
X757287Y1380873D03*
Y1385873D03*
Y1390873D03*
Y1395873D03*
Y1400873D03*
Y1405873D03*
Y1410873D03*
Y1415873D03*
Y1420873D03*
Y1425873D03*
Y1430873D03*
Y1435873D03*
Y1440873D03*
Y1445873D03*
X766156Y1462004D03*
X771156D03*
X790500Y1466500D03*
X786000Y1463500D03*
X756287Y1459264D03*
Y1454264D03*
X779547Y1463004D03*
X792902Y1477964D03*
Y1487964D03*
Y1497964D03*
Y1507964D03*
Y1517964D03*
Y1512964D03*
Y1472964D03*
Y1482964D03*
Y1492964D03*
Y1502964D03*
Y1562964D03*
Y1527964D03*
Y1537964D03*
Y1547964D03*
Y1557964D03*
Y1567964D03*
Y1522964D03*
Y1532964D03*
Y1542964D03*
Y1552964D03*
Y1612964D03*
Y1602964D03*
Y1592964D03*
Y1582964D03*
Y1572964D03*
Y1577964D03*
Y1587964D03*
Y1597964D03*
Y1607964D03*
X797902Y1652964D03*
X792902D03*
Y1642964D03*
Y1632964D03*
Y1622964D03*
Y1627964D03*
Y1637964D03*
Y1647964D03*
Y1617964D03*
X872642Y-140575D03*
Y-135575D03*
Y-130575D03*
Y-125575D03*
X890264Y-147256D03*
X880264D03*
X875264D03*
X885264D03*
X895264D03*
X872642Y-80575D03*
Y-120575D03*
Y-115575D03*
Y-110575D03*
Y-105575D03*
Y-100575D03*
Y-95575D03*
Y-90575D03*
Y-85575D03*
Y-30575D03*
Y-35575D03*
Y-40575D03*
Y-45575D03*
Y-50575D03*
Y-55575D03*
Y-60575D03*
Y-65575D03*
Y-70575D03*
Y-75575D03*
Y-20575D03*
Y-25575D03*
X940264Y-147256D03*
X930264D03*
X925264D03*
X935264D03*
X920264D03*
X910264D03*
X900264D03*
X905264D03*
X915264D03*
X960264D03*
X950264D03*
X955264D03*
X965264D03*
X945264D03*
X990264D03*
X980264D03*
X970264D03*
X975264D03*
X985264D03*
X1010264D03*
X1000264D03*
X1005264D03*
X1015264D03*
X995264D03*
X1040264D03*
X1030264D03*
X1020264D03*
X1025264D03*
X1035264D03*
X1060264D03*
X1050264D03*
X1055264D03*
X1065264D03*
X1045264D03*
X1080264D03*
X1070264D03*
X1075264D03*
X1085264D03*
X1078098Y1652768D03*
X1073098D03*
X1083098D03*
X1088098D03*
X1110264Y-147256D03*
X1100264D03*
X1090264D03*
X1105264D03*
X1095264D03*
X1130264D03*
X1120264D03*
X1115264D03*
X1125264D03*
X1135264D03*
X1093098Y1652768D03*
X1133098D03*
X1123098D03*
X1113098D03*
X1103098D03*
X1108098D03*
X1118098D03*
X1128098D03*
X1098098D03*
X1170264Y-147256D03*
X1155264D03*
X1175602Y-137594D03*
Y-127594D03*
X1160264Y-147256D03*
X1150264D03*
X1140264D03*
X1145264D03*
X1175602Y-132594D03*
Y-142594D03*
X1165264Y-147256D03*
X1175602Y-117594D03*
Y-107594D03*
Y-97594D03*
Y-87594D03*
Y-77594D03*
Y-82594D03*
Y-92594D03*
Y-102594D03*
Y-112594D03*
Y-122594D03*
Y-67594D03*
Y-57594D03*
Y-47594D03*
Y-37594D03*
Y-32594D03*
Y-42594D03*
Y-52594D03*
Y-62594D03*
Y-72594D03*
Y-17594D03*
Y-27594D03*
X1180500Y4000D03*
X1176500Y-500D03*
X1175602Y-22594D03*
Y-12594D03*
Y-7594D03*
X1162000Y1371500D03*
X1169783Y1369303D03*
X1179783D03*
X1174783D03*
X1184783D03*
X1158673Y1417067D03*
Y1407067D03*
Y1397067D03*
Y1387067D03*
Y1377067D03*
Y1412067D03*
Y1402067D03*
Y1392067D03*
Y1382067D03*
Y1422067D03*
Y1442067D03*
Y1452067D03*
X1158500Y1468500D03*
X1158673Y1457067D03*
Y1447067D03*
Y1437067D03*
Y1427067D03*
Y1462067D03*
Y1432067D03*
X1161000Y1474500D03*
X1166673Y1477941D03*
X1171673D03*
X1181673D03*
X1176673D03*
X1143098Y1652768D03*
X1183098D03*
X1173098D03*
X1163098D03*
X1153098D03*
X1158098D03*
X1168098D03*
X1178098D03*
X1138098D03*
X1148098D03*
X1191382Y5500D03*
X1196382D03*
X1186382D03*
X1201382D03*
X1211382D03*
X1221382D03*
X1231382D03*
X1226382D03*
X1216382D03*
X1206382D03*
X1199783Y1369303D03*
X1209783D03*
X1219783D03*
X1229783D03*
X1189783D03*
X1224783D03*
X1214783D03*
X1204783D03*
X1194783D03*
X1191673Y1477941D03*
X1201673D03*
X1214972Y1482642D03*
Y1517642D03*
Y1487642D03*
Y1497642D03*
Y1507642D03*
Y1512642D03*
Y1502642D03*
Y1492642D03*
X1206673Y1477941D03*
X1196673D03*
X1186673D03*
X1211673D03*
X1214972Y1567642D03*
Y1527642D03*
Y1537642D03*
Y1547642D03*
Y1557642D03*
Y1562642D03*
Y1552642D03*
Y1542642D03*
Y1532642D03*
Y1522642D03*
Y1577642D03*
Y1587642D03*
Y1597642D03*
Y1607642D03*
Y1612642D03*
Y1602642D03*
Y1592642D03*
Y1582642D03*
Y1572642D03*
Y1617642D03*
Y1627642D03*
Y1637642D03*
X1213098Y1652768D03*
X1193098D03*
X1203098D03*
X1208098D03*
X1214972Y1642642D03*
Y1632642D03*
X1188098Y1652768D03*
X1198098D03*
X1214972Y1622642D03*
Y1647642D03*
X1251382Y5500D03*
X1261382D03*
X1271382D03*
X1281382D03*
X1276382D03*
X1266382D03*
X1256382D03*
X1241382D03*
X1246382D03*
X1236382D03*
X1249783Y1369303D03*
X1259783D03*
X1269783D03*
X1279783D03*
X1239783D03*
X1274783D03*
X1264783D03*
X1254783D03*
X1234783D03*
X1244783D03*
X1301382Y5500D03*
X1311382D03*
X1296382D03*
X1316382D03*
X1306382D03*
X1291382D03*
X1286382D03*
X1326382D03*
X1321382D03*
X1299783Y1369303D03*
X1309783D03*
X1319783D03*
X1329783D03*
X1289783D03*
X1324783D03*
X1314783D03*
X1304783D03*
X1294783D03*
X1284783D03*
X1363579Y19821D03*
Y14821D03*
Y9821D03*
X1351382Y5500D03*
X1356382D03*
X1346382D03*
X1336382D03*
X1341382D03*
X1331382D03*
X1363579Y44821D03*
Y39821D03*
Y34821D03*
Y29821D03*
Y24821D03*
X1374000Y64500D03*
X1363579Y51618D03*
X1349783Y1369303D03*
X1359783D03*
X1369783D03*
X1339783D03*
X1374783D03*
X1364783D03*
X1354783D03*
X1344783D03*
X1334783D03*
X1399783D03*
X1409783D03*
X1419783D03*
X1379783D03*
X1389783D03*
X1404783D03*
X1414783D03*
X1424783D03*
X1394783D03*
X1384783D03*
X1434441Y590424D03*
X1434581Y586136D03*
X1449783Y1369303D03*
X1459783D03*
X1469783D03*
X1429783D03*
X1439783D03*
X1444783D03*
X1454783D03*
X1464783D03*
X1474783D03*
X1434783D03*
X1499783D03*
X1509783D03*
X1519783D03*
X1479783D03*
X1489783D03*
X1494783D03*
X1484783D03*
X1504783D03*
X1514783D03*
X1565555Y16517D03*
X1568030Y5500D03*
X1565555Y21517D03*
Y26517D03*
Y31517D03*
Y36517D03*
Y41517D03*
X1557000Y64500D03*
X1561500Y62000D03*
X1564000Y57500D03*
X1564555Y52124D03*
X1549783Y1369303D03*
X1559783D03*
X1569783D03*
X1529783D03*
X1539783D03*
X1524783D03*
X1534783D03*
X1544783D03*
X1554783D03*
X1564783D03*
X1603030Y5500D03*
X1613030D03*
X1573030D03*
X1583030D03*
X1593030D03*
X1618030D03*
X1608030D03*
X1598030D03*
X1588030D03*
X1578030D03*
X1614783Y1369303D03*
X1604783D03*
X1599783D03*
X1609783D03*
X1619783D03*
X1579783D03*
X1589783D03*
X1574783D03*
X1584783D03*
X1594783D03*
X1653030Y5500D03*
X1663030D03*
X1623030D03*
X1633030D03*
X1643030D03*
X1668030D03*
X1658030D03*
X1648030D03*
X1638030D03*
X1628030D03*
X1664783Y1369303D03*
X1654783D03*
X1644783D03*
X1634783D03*
X1624783D03*
X1649783D03*
X1659783D03*
X1629783D03*
X1639783D03*
X1703030Y5500D03*
X1713030D03*
X1673030D03*
X1683030D03*
X1693030D03*
X1718030D03*
X1708030D03*
X1698030D03*
X1688030D03*
X1678030D03*
X1714783Y1369303D03*
X1704783D03*
X1694783D03*
X1684783D03*
X1674783D03*
X1699783D03*
X1709783D03*
X1669783D03*
X1679783D03*
X1689783D03*
X1753030Y5500D03*
X1763030D03*
X1723030D03*
X1733030D03*
X1743030D03*
X1758030D03*
X1748030D03*
X1738030D03*
X1728030D03*
X1764783Y1369303D03*
X1754783D03*
X1744783D03*
X1734783D03*
X1724783D03*
X1749783D03*
X1759783D03*
X1719783D03*
X1729783D03*
X1739783D03*
X1778030Y5500D03*
X1793030D03*
X1803030D03*
X1813030D03*
X1808030D03*
X1798030D03*
X1783030D03*
X1788030D03*
X1773030D03*
X1768030D03*
X1804783Y1369303D03*
X1794783D03*
X1784783D03*
X1774783D03*
X1799783D03*
X1809783D03*
X1769783D03*
X1779783D03*
X1789783D03*
X1843030Y5500D03*
X1853030D03*
X1863030D03*
X1838030D03*
X1858030D03*
X1848030D03*
X1823030D03*
X1833030D03*
X1828030D03*
X1818030D03*
X1854783Y1369303D03*
X1844783D03*
X1834783D03*
X1824783D03*
X1814783D03*
X1849783D03*
X1859783D03*
X1819783D03*
X1829783D03*
X1839783D03*
X1878030Y5500D03*
X1883030D03*
X1873030D03*
X1868030D03*
X1909030D03*
X1888030D03*
X1904783Y1369303D03*
X1894783D03*
X1884783D03*
X1874783D03*
X1864783D03*
X1899783D03*
X1909783D03*
X1869783D03*
X1879783D03*
X1889783D03*
X1929343Y16525D03*
Y11525D03*
Y6525D03*
X1914030Y5500D03*
X1919030D03*
X1924030D03*
X1929343Y46525D03*
Y41525D03*
Y36525D03*
Y31525D03*
Y26525D03*
Y21525D03*
Y66525D03*
Y61525D03*
Y56525D03*
Y51525D03*
Y116525D03*
Y111525D03*
Y106525D03*
Y101525D03*
Y96525D03*
Y91525D03*
Y86525D03*
Y81525D03*
Y76525D03*
Y71525D03*
Y121525D03*
Y126525D03*
Y136525D03*
Y146525D03*
Y156525D03*
Y161525D03*
Y151525D03*
Y141525D03*
Y131525D03*
Y176525D03*
Y186525D03*
Y196525D03*
Y206525D03*
Y166525D03*
Y211525D03*
Y201525D03*
Y191525D03*
Y181525D03*
Y171525D03*
Y226525D03*
Y236525D03*
Y246525D03*
Y256525D03*
Y216525D03*
Y261525D03*
Y251525D03*
Y241525D03*
Y231525D03*
Y221525D03*
Y276525D03*
Y286525D03*
Y296525D03*
Y306525D03*
Y266525D03*
Y301525D03*
Y291525D03*
Y281525D03*
Y271525D03*
Y326525D03*
Y336525D03*
Y346525D03*
Y356525D03*
Y316525D03*
Y351525D03*
Y341525D03*
Y331525D03*
Y321525D03*
Y311525D03*
Y376525D03*
Y386525D03*
Y396525D03*
Y406525D03*
Y366525D03*
Y401525D03*
Y391525D03*
Y381525D03*
Y371525D03*
Y361525D03*
Y426525D03*
Y436525D03*
Y446525D03*
Y416525D03*
Y451525D03*
Y441525D03*
Y431525D03*
Y421525D03*
Y411525D03*
Y476525D03*
Y486525D03*
Y496525D03*
Y456525D03*
Y466525D03*
Y501525D03*
Y491525D03*
Y481525D03*
Y471525D03*
Y461525D03*
Y526525D03*
Y536525D03*
Y546525D03*
Y506525D03*
Y516525D03*
Y551525D03*
Y541525D03*
Y531525D03*
Y521525D03*
Y511525D03*
Y576525D03*
Y586525D03*
Y596525D03*
Y556525D03*
Y566525D03*
Y591525D03*
Y581525D03*
Y571525D03*
Y561525D03*
Y626525D03*
Y636525D03*
Y646525D03*
Y606525D03*
Y616525D03*
Y641525D03*
Y631525D03*
Y621525D03*
Y611525D03*
Y601525D03*
Y676525D03*
Y686525D03*
Y696525D03*
Y656525D03*
Y666525D03*
Y691525D03*
Y681525D03*
Y671525D03*
Y661525D03*
Y651525D03*
Y726525D03*
Y736525D03*
Y706525D03*
Y716525D03*
Y741525D03*
Y731525D03*
Y721525D03*
Y711525D03*
Y701525D03*
Y776525D03*
Y786525D03*
Y746525D03*
Y756525D03*
Y766525D03*
Y791525D03*
Y781525D03*
Y771525D03*
Y761525D03*
Y751525D03*
Y826525D03*
Y836525D03*
Y796525D03*
Y806525D03*
Y816525D03*
Y841525D03*
Y831525D03*
Y821525D03*
Y811525D03*
Y801525D03*
Y876525D03*
Y886525D03*
Y846525D03*
Y856525D03*
Y866525D03*
Y881525D03*
Y871525D03*
Y861525D03*
Y851525D03*
Y926525D03*
Y896525D03*
Y906525D03*
Y916525D03*
Y931525D03*
Y921525D03*
Y911525D03*
Y901525D03*
Y891525D03*
Y936525D03*
Y973863D03*
Y978863D03*
Y983863D03*
Y951525D03*
Y956525D03*
Y961525D03*
Y966525D03*
Y946525D03*
Y941525D03*
Y988863D03*
Y993863D03*
Y998863D03*
Y1003863D03*
Y1008863D03*
Y1033863D03*
Y1028863D03*
Y1023863D03*
Y1018863D03*
Y1013863D03*
Y1073863D03*
Y1083863D03*
Y1043863D03*
Y1053863D03*
Y1063863D03*
Y1078863D03*
Y1068863D03*
Y1058863D03*
Y1048863D03*
Y1038863D03*
Y1123863D03*
Y1093863D03*
Y1103863D03*
Y1113863D03*
Y1128863D03*
Y1118863D03*
Y1108863D03*
Y1098863D03*
Y1088863D03*
Y1173863D03*
Y1133863D03*
Y1143863D03*
Y1153863D03*
Y1163863D03*
Y1178863D03*
Y1168863D03*
Y1158863D03*
Y1148863D03*
Y1138863D03*
Y1223863D03*
Y1183863D03*
Y1193863D03*
Y1203863D03*
Y1213863D03*
Y1228863D03*
Y1218863D03*
Y1208863D03*
Y1198863D03*
Y1188863D03*
Y1273863D03*
Y1233863D03*
Y1243863D03*
Y1253863D03*
Y1263863D03*
Y1268863D03*
Y1258863D03*
Y1248863D03*
Y1238863D03*
Y1323863D03*
Y1283863D03*
Y1293863D03*
Y1303863D03*
Y1313863D03*
Y1318863D03*
Y1308863D03*
Y1298863D03*
Y1288863D03*
Y1278863D03*
Y1333863D03*
Y1343863D03*
Y1353863D03*
X1924783Y1369303D03*
X1914783D03*
X1919783D03*
X1929343Y1358863D03*
Y1348863D03*
Y1338863D03*
Y1328863D03*
Y1363863D03*
G54D20*
G01X458071Y73819D02*
Y72200D01*
G03X458217Y71847I500J0D01*
G01X458279Y71785D01*
G03X458632Y71639I353J354D01*
G01X460276D01*
G03X460629Y71785I0J500D01*
G01X460893Y72049D01*
G03X461039Y72402I-354J353D01*
G01Y130983D01*
X480160Y160016D01*
X513737Y182238D01*
Y182239D01*
X547116Y204331D01*
X547117D01*
X568499Y218483D01*
X683763Y242013D01*
X795747Y218547D01*
X891689Y237607D01*
X927438Y265142D01*
X930796D01*
X934733Y269079D01*
X948369D01*
G02X950932Y267927I1J-3424D01*
G01X951253Y267285D01*
G03X951991Y267039I492J246D01*
G01X954921Y268504D01*
G01X458071Y68307D02*
Y69987D01*
G02X458175Y70238I355J0D01*
G01X458279Y70342D01*
G02X458632Y70488I353J-354D01*
G01X458633Y70489D01*
X460276D01*
G03X461443Y70971I1J1650D01*
G01X461707Y71236D01*
G03X462189Y72402I-1168J1165D01*
G01Y130638D01*
X480992Y159186D01*
X568948Y217400D01*
X683760Y240838D01*
X795741Y217373D01*
X892178Y236531D01*
X902012Y244106D01*
X911632Y251515D01*
X912403Y251415D01*
X913710Y252422D01*
X913810Y253193D01*
X915117Y254200D01*
X915889Y254100D01*
X917196Y255107D01*
X917296Y255878D01*
X918603Y256885D01*
X919375Y256785D01*
X920682Y257792D01*
X920782Y258563D01*
X927830Y263992D01*
X931273D01*
X935210Y267929D01*
X948370D01*
G02X949978Y267263I0J-2274D01*
G01X950224Y266771D01*
G02X949978Y266033I-492J-246D01*
G01X947047Y264567D01*
G01X450984Y77756D02*
Y76137D01*
G03X451130Y75784I500J0D01*
G01X451192Y75722D01*
G03X451545Y75576I353J354D01*
G01X453189D01*
G03X453542Y75722I0J500D01*
G01X453806Y75986D01*
G03X453952Y76339I-354J353D01*
G01Y128727D01*
X498469Y196366D01*
X611593Y271031D01*
X802312Y308930D01*
X928805Y280890D01*
X930796D01*
X934733Y284827D01*
X948369D01*
G02X950932Y283675I1J-3424D01*
G01X951253Y283033D01*
G03X951991Y282787I492J246D01*
G01X954921Y284252D01*
G01X450984Y72245D02*
Y73864D01*
G02X451130Y74217I500J0D01*
G01X451192Y74279D01*
G02X451545Y74425I353J-354D01*
G01X451546Y74426D01*
X453189D01*
G03X454356Y74908I1J1650D01*
G01X454620Y75173D01*
G03X455102Y76339I-1168J1165D01*
G01Y128382D01*
X499300Y195536D01*
X612039Y269946D01*
X802299Y307754D01*
X856336Y295775D01*
X903511Y285319D01*
X903929Y284663D01*
X905539Y284306D01*
X906195Y284724D01*
X907806Y284367D01*
X908224Y283711D01*
X909835Y283354D01*
X910491Y283771D01*
X912102Y283414D01*
X912520Y282758D01*
X914131Y282401D01*
X914787Y282819D01*
X928679Y279740D01*
X931273D01*
X935210Y283677D01*
X948370D01*
G02X949978Y283011I0J-2274D01*
G01X950224Y282519D01*
G02X949978Y281781I-492J-246D01*
G01X947047Y280315D01*
G01X443898Y73819D02*
Y72200D01*
G03X444044Y71847I500J0D01*
G01X444106Y71785D01*
G03X444459Y71639I353J354D01*
G01X446103D01*
G03X446456Y71785I0J500D01*
G01X446720Y72049D01*
G03X446866Y72402I-354J353D01*
G01Y125687D01*
X500161Y206633D01*
X560109Y247070D01*
Y247069D01*
X620061Y287508D01*
X800168Y323281D01*
X927337Y296638D01*
X931398D01*
X935335Y300575D01*
X948369D01*
G02X950932Y299423I1J-3424D01*
G01X951253Y298781D01*
G03X951991Y298535I492J246D01*
G01X954921Y300000D01*
G01X443898Y68307D02*
Y69987D01*
G02X444002Y70238I355J0D01*
G01X444106Y70342D01*
G02X444459Y70488I353J-354D01*
G01X444460Y70489D01*
X446103D01*
G03X447270Y70971I1J1650D01*
G01X447534Y71236D01*
G03X448016Y72402I-1168J1165D01*
G01Y125342D01*
X500995Y205808D01*
X620512Y286425D01*
X800162Y322107D01*
X899579Y301278D01*
X900005Y300627D01*
X901620Y300289D01*
X902271Y300714D01*
X903886Y300376D01*
X904311Y299725D01*
X905926Y299387D01*
X906578Y299812D01*
X908192Y299474D01*
X908618Y298823D01*
X910233Y298484D01*
X910884Y298910D01*
X927217Y295488D01*
X931875D01*
X935812Y299425D01*
X948370D01*
G02X949978Y298759I0J-2274D01*
G01X950224Y298267D01*
G02X949978Y297529I-492J-246D01*
G01X947047Y296063D01*
G01X436811Y77756D02*
Y76137D01*
G03X436957Y75784I500J0D01*
G01X437019Y75722D01*
G03X437372Y75576I353J354D01*
G01X439016D01*
G03X439369Y75722I0J500D01*
G01X439633Y75986D01*
G03X439779Y76339I-354J353D01*
G01Y126291D01*
X493800Y208329D01*
X618946Y292744D01*
X825697Y333809D01*
X911049Y315926D01*
X913033Y315510D01*
Y315509D01*
X914378Y315227D01*
X927938Y312386D01*
X931259D01*
X935196Y316323D01*
X948369D01*
G02X950932Y315171I1J-3424D01*
G01X951253Y314529D01*
G03X951991Y314283I492J246D01*
G01X954921Y315748D01*
G01X436811Y72245D02*
Y73864D01*
G02X436957Y74217I500J0D01*
G01X437019Y74279D01*
G02X437372Y74425I353J-354D01*
G01X437373Y74426D01*
X439016D01*
G03X440183Y74908I1J1650D01*
G01X440447Y75173D01*
G03X440929Y76339I-1168J1165D01*
G01Y125946D01*
X494634Y207504D01*
X619397Y291661D01*
X825691Y332635D01*
X912796Y314384D01*
X912797Y314383D01*
X913222Y313732D01*
X914837Y313394D01*
X915488Y313819D01*
X917103Y313481D01*
X917529Y312830D01*
X919144Y312492D01*
X919795Y312917D01*
X921410Y312579D01*
X921835Y311928D01*
X923450Y311589D01*
X924101Y312015D01*
X927818Y311236D01*
X931736D01*
X935673Y315173D01*
X948370D01*
G02X949978Y314507I0J-2274D01*
G01X950224Y314015D01*
G02X949978Y313277I-492J-246D01*
G01X947047Y311811D01*
G01X429724Y73819D02*
Y72200D01*
G03X429870Y71847I500J0D01*
G01X429932Y71785D01*
G03X430285Y71639I353J354D01*
G01X431929D01*
G03X432282Y71785I0J500D01*
G01X432546Y72049D01*
G03X432692Y72402I-354J353D01*
G01Y139952D01*
G02X432783Y140255I550J0D01*
G01X471799Y199510D01*
G02X471951Y199664I460J-302D01*
G01X618370Y298422D01*
X848601Y344152D01*
X925052Y328134D01*
X931398D01*
X935335Y332071D01*
X948369D01*
G02X950932Y330919I1J-3424D01*
G01X951253Y330277D01*
G03X951991Y330031I492J246D01*
G01X954921Y331496D01*
G01X429724Y68307D02*
Y69927D01*
G02X429870Y70280I500J0D01*
G01X429932Y70342D01*
G02X430285Y70488I353J-354D01*
G01X430286Y70489D01*
X431929D01*
G03X433096Y70971I1J1650D01*
G01X433360Y71236D01*
G03X433842Y72402I-1168J1165D01*
G01Y139772D01*
X472694Y198777D01*
X618821Y297339D01*
X848595Y342978D01*
X881736Y336033D01*
X905036Y331152D01*
X905462Y330501D01*
X907077Y330163D01*
X907728Y330588D01*
X909343Y330250D01*
X909768Y329599D01*
X911383Y329261D01*
X912034Y329686D01*
X913649Y329348D01*
X914075Y328697D01*
X915690Y328358D01*
X916341Y328784D01*
X924932Y326984D01*
X931875D01*
X935812Y330921D01*
X948370D01*
G02X949978Y330255I0J-2274D01*
G01X950224Y329763D01*
G02X949978Y329025I-492J-246D01*
G01X947047Y327559D01*
G01X479331Y77756D02*
Y76137D01*
G03X479477Y75784I500J0D01*
G01X479539Y75722D01*
G03X479892Y75576I353J354D01*
G01X481536D01*
G03X481889Y75722I0J500D01*
G01X482153Y75986D01*
G03X482299Y76339I-354J353D01*
G01Y117776D01*
X482694Y119714D01*
X491062Y132358D01*
X614125Y195756D01*
X695425Y212188D01*
X790115Y192922D01*
X916529Y217898D01*
X930796D01*
X934733Y221835D01*
X948369D01*
G02X950932Y220683I1J-3424D01*
G01X951253Y220041D01*
G03X951991Y219795I492J246D01*
G01X954921Y221260D01*
G01X479331Y72245D02*
Y73864D01*
G02X479477Y74217I500J0D01*
G01X479539Y74279D01*
G02X479892Y74425I353J-354D01*
G01X479893Y74426D01*
X481536D01*
G03X482703Y74908I1J1650D01*
G01X482967Y75173D01*
G03X483449Y76339I-1168J1165D01*
G01Y117657D01*
X483777Y119265D01*
X491856Y131472D01*
X614510Y194660D01*
X695424Y211014D01*
X790112Y191749D01*
X888102Y211109D01*
X888748Y210676D01*
X890367Y210996D01*
X890800Y211642D01*
X892418Y211962D01*
X893065Y211529D01*
X894683Y211849D01*
X895116Y212495D01*
X896735Y212815D01*
X897381Y212382D01*
X899000Y212702D01*
X899433Y213348D01*
X916642Y216748D01*
X931273D01*
X935210Y220685D01*
X948370D01*
G02X949978Y220019I0J-2274D01*
G01X950224Y219527D01*
G02X949978Y218789I-492J-246D01*
G01X947047Y217323D01*
G01X472244Y73819D02*
Y72200D01*
G03X472390Y71847I500J0D01*
G01X472452Y71785D01*
G03X472805Y71639I353J354D01*
G01X474449D01*
G03X474802Y71785I0J500D01*
G01X475066Y72049D01*
G03X475212Y72402I-354J353D01*
G01Y123817D01*
X484965Y138627D01*
X604896Y200410D01*
X695859Y218913D01*
X772028Y202978D01*
X928274Y233646D01*
X930796D01*
X934733Y237583D01*
X948369D01*
G02X950932Y236431I1J-3424D01*
G01X951253Y235789D01*
G03X951991Y235543I492J246D01*
G01X954921Y237008D01*
G01X472244Y68307D02*
Y69987D01*
G02X472348Y70238I355J0D01*
G01X472452Y70342D01*
G02X472805Y70488I353J-354D01*
G01X472806Y70489D01*
X474449D01*
G03X475616Y70971I1J1650D01*
G01X475880Y71236D01*
G03X476362Y72402I-1168J1165D01*
G01Y123472D01*
X485760Y137742D01*
X590230Y191561D01*
X605282Y199314D01*
X695856Y217738D01*
X772021Y201804D01*
X895864Y226112D01*
X896510Y225678D01*
X898129Y225996D01*
X898563Y226642D01*
X900182Y226959D01*
X900827Y226526D01*
X902446Y226843D01*
X902880Y227489D01*
X904499Y227807D01*
X905145Y227373D01*
X906764Y227691D01*
X907198Y228337D01*
X928386Y232496D01*
X931273D01*
X935210Y236433D01*
X948370D01*
G02X949978Y235767I0J-2274D01*
G01X950224Y235275D01*
G02X949978Y234537I-492J-246D01*
G01X947047Y233071D01*
G01X465157Y77756D02*
Y76137D01*
G03X465303Y75784I500J0D01*
G01X465365Y75722D01*
G03X465718Y75576I353J354D01*
G01X467362D01*
G03X467715Y75722I0J500D01*
G01X467979Y75986D01*
G03X468125Y76339I-354J353D01*
G01Y120692D01*
X497986Y166044D01*
X525698Y184742D01*
X525699Y184743D01*
X553412Y203441D01*
X699409Y232356D01*
X794170Y212565D01*
X900353Y233800D01*
X920599Y249394D01*
X930796D01*
X934733Y253331D01*
X948369D01*
G02X950932Y252179I1J-3424D01*
G01X951253Y251537D01*
G03X951991Y251291I492J246D01*
G01X954921Y252756D01*
G01X465157Y72245D02*
Y73864D01*
G02X465303Y74217I500J0D01*
G01X465365Y74279D01*
G02X465718Y74425I353J-354D01*
G01X465719Y74426D01*
X467362D01*
G03X468529Y74908I1J1650D01*
G01X468793Y75173D01*
G03X469275Y76339I-1168J1165D01*
G01Y120347D01*
X498820Y165219D01*
X553863Y202357D01*
X699403Y231182D01*
X794165Y211391D01*
X900842Y232725D01*
X905326Y236178D01*
X909596Y239467D01*
X910367Y239367D01*
X911674Y240374D01*
X911774Y241145D01*
X913082Y242152D01*
X913853Y242052D01*
X915160Y243059D01*
X915260Y243830D01*
X916568Y244837D01*
X917339Y244737D01*
X918646Y245744D01*
X918746Y246515D01*
X920991Y248244D01*
X931273D01*
X935210Y252181D01*
X948370D01*
G02X949978Y251515I0J-2274D01*
G01X950224Y251023D01*
G02X949978Y250285I-492J-246D01*
G01X947047Y248819D01*
G01X550197Y77756D02*
Y76137D01*
G03X550343Y75784I500J0D01*
G01X550405Y75722D01*
G03X550758Y75576I353J354D01*
G01X552402D01*
G03X552755Y75722I0J500D01*
G01X553019Y75986D01*
G03X553165Y76339I-354J353D01*
G01Y124694D01*
X554858Y127261D01*
X558162Y129490D01*
X561469Y131721D01*
X632171Y145850D01*
X859410Y101713D01*
X928522Y115536D01*
X930724D01*
X934661Y119473D01*
X948440D01*
X952377Y123410D01*
X956660D01*
X963237Y129987D01*
X970968Y141582D01*
X987296Y225637D01*
X987298D01*
X964857Y341085D01*
Y341086D01*
X958330Y350727D01*
X919252Y382153D01*
X910317Y395917D01*
X871222Y572354D01*
X883701Y627497D01*
X923354Y688556D01*
X927201Y691519D01*
X931019D01*
X934956Y695456D01*
X948369D01*
G02X950932Y694304I1J-3424D01*
G01X951253Y693662D01*
G03X951991Y693416I492J246D01*
G01X954921Y694881D01*
G01X550197Y72245D02*
Y73864D01*
G02X550343Y74217I500J0D01*
G01X550405Y74279D01*
G02X550758Y74425I353J-354D01*
G01X550759Y74426D01*
X552402D01*
G03X553569Y74908I1J1650D01*
G01X553833Y75173D01*
G03X554315Y76339I-1168J1165D01*
G01Y124348D01*
X555692Y126436D01*
X561920Y130637D01*
X561921Y130638D01*
X632174Y144677D01*
X859413Y100540D01*
X928636Y114386D01*
X931201D01*
X935138Y118323D01*
X948917D01*
X952854Y122260D01*
X957137D01*
X964131Y129254D01*
X972053Y141136D01*
X988468Y225637D01*
X988470D01*
X965942Y341536D01*
X965810Y341731D01*
X959186Y351516D01*
X920117Y382934D01*
X911395Y396369D01*
X872401Y572351D01*
X878590Y599699D01*
X878591D01*
X884778Y627042D01*
X916690Y676181D01*
X917450Y676343D01*
X918349Y677726D01*
X918187Y678487D01*
X919086Y679871D01*
X919847Y680032D01*
X920745Y681416D01*
X920584Y682177D01*
X921482Y683561D01*
X922243Y683722D01*
X923142Y685106D01*
X922980Y685867D01*
X924212Y687764D01*
X927593Y690369D01*
X931496D01*
X935433Y694306D01*
X948370D01*
G02X949978Y693640I0J-2274D01*
G01X950224Y693148D01*
G02X949978Y692410I-492J-246D01*
G01X947047Y690944D01*
G01X543110Y73819D02*
Y72200D01*
G03X543256Y71847I500J0D01*
G01X543318Y71785D01*
G03X543671Y71639I353J354D01*
G01X545315D01*
G03X545668Y71785I0J500D01*
G01X545932Y72049D01*
G03X546078Y72402I-354J353D01*
G01Y125758D01*
X546807Y126866D01*
X546808Y126867D01*
X547474Y127879D01*
X560266Y136504D01*
X634586Y151346D01*
X854256Y108646D01*
X928537Y123410D01*
X930724D01*
X934661Y127347D01*
X948440D01*
X952377Y131284D01*
X956561D01*
X960388Y135111D01*
X964676Y141469D01*
X981955Y230397D01*
X961068Y337895D01*
X960192Y339090D01*
X958441Y341478D01*
X954018Y347514D01*
X913871Y379803D01*
X904885Y393643D01*
X865092Y573239D01*
X879133Y635294D01*
X924379Y704959D01*
X925168Y705567D01*
X927374Y707267D01*
X931019D01*
X934956Y711204D01*
X948369D01*
G02X950932Y710052I1J-3424D01*
G01X951253Y709410D01*
G03X951991Y709164I492J246D01*
G01X954921Y710629D01*
G01X543110Y68307D02*
Y69927D01*
G02X543256Y70280I500J0D01*
G01X543318Y70342D01*
G02X543671Y70488I353J-354D01*
G01X543672Y70489D01*
X545315D01*
G03X546482Y70971I1J1650D01*
G01X546746Y71236D01*
G03X547228Y72402I-1168J1165D01*
G01Y125413D01*
X548308Y127054D01*
X560718Y135421D01*
X634589Y150173D01*
X854258Y107473D01*
X928651Y122260D01*
X931201D01*
X935138Y126197D01*
X948917D01*
X952854Y130134D01*
X957038D01*
X961280Y134376D01*
X965761Y141020D01*
X983127Y230397D01*
X962148Y338367D01*
X961558Y339173D01*
X961120Y339771D01*
X959369Y342158D01*
X954857Y348316D01*
X914736Y380584D01*
X905963Y394095D01*
X866271Y573236D01*
X873241Y604040D01*
X873242D01*
X880210Y634839D01*
X916511Y690733D01*
X917272Y690895D01*
X918171Y692278D01*
X918009Y693039D01*
X918908Y694423D01*
X919669Y694585D01*
X920568Y695968D01*
X920406Y696729D01*
X921305Y698113D01*
X922065Y698275D01*
X922964Y699658D01*
X922802Y700419D01*
X925237Y704168D01*
X927766Y706117D01*
X931496D01*
X935433Y710054D01*
X948370D01*
G02X949978Y709388I0J-2274D01*
G01X950224Y708896D01*
G02X949978Y708158I-492J-246D01*
G01X947047Y706692D01*
G01X536024Y77756D02*
Y76137D01*
G03X536170Y75784I500J0D01*
G01X536232Y75722D01*
G03X536585Y75576I353J354D01*
G01X538229D01*
G03X538582Y75722I0J500D01*
G01X538846Y75986D01*
G03X538992Y76339I-354J353D01*
G01Y124079D01*
X544474Y132403D01*
X577866Y154929D01*
X577867D01*
X620922Y163477D01*
X794332Y129768D01*
X921000Y154906D01*
X931398D01*
X935335Y158843D01*
X948369D01*
G02X950932Y157691I1J-3424D01*
G01X951253Y157049D01*
G03X951991Y156803I492J246D01*
G01X954921Y158268D01*
G01X536024Y72245D02*
Y73864D01*
G02X536170Y74217I500J0D01*
G01X536232Y74279D01*
G02X536585Y74425I353J-354D01*
G01X536586Y74426D01*
X538229D01*
G03X539396Y74908I1J1650D01*
G01X539660Y75173D01*
G03X540142Y76339I-1168J1165D01*
G01Y123734D01*
X545308Y131578D01*
X578317Y153845D01*
X578318Y153846D01*
X620924Y162304D01*
X794334Y128595D01*
X904100Y150379D01*
X904746Y149947D01*
X906365Y150268D01*
X906797Y150915D01*
X908416Y151236D01*
X909062Y150804D01*
X910681Y151125D01*
X911113Y151771D01*
X912732Y152092D01*
X913378Y151660D01*
X914997Y151981D01*
X915429Y152628D01*
X921114Y153756D01*
X931875D01*
X935812Y157693D01*
X948370D01*
G02X949978Y157027I0J-2274D01*
G01X950224Y156535D01*
G02X949978Y155797I-492J-246D01*
G01X947047Y154331D01*
G01X528937Y73819D02*
Y72200D01*
G03X529083Y71847I500J0D01*
G01X529145Y71785D01*
G03X529498Y71639I353J354D01*
G01X531142D01*
G03X531495Y71785I0J500D01*
G01X531759Y72049D01*
G03X531905Y72402I-354J353D01*
G01Y124681D01*
X537140Y132631D01*
X577175Y159635D01*
X620702Y168488D01*
X767716Y139909D01*
X898723Y165948D01*
X898724D01*
X922398Y170654D01*
X931028D01*
X934965Y174591D01*
X948369D01*
G02X950932Y173439I1J-3424D01*
G01X951253Y172797D01*
G03X951991Y172551I492J246D01*
G01X954921Y174016D01*
G01X528937Y68307D02*
Y69927D01*
G02X529083Y70280I500J0D01*
G01X529145Y70342D01*
G02X529498Y70488I353J-354D01*
G01X529499Y70489D01*
X531142D01*
G03X532309Y70971I1J1650D01*
G01X532573Y71236D01*
G03X533055Y72402I-1168J1165D01*
G01Y124336D01*
X537974Y131806D01*
X577629Y158553D01*
X620707Y167315D01*
X767718Y138736D01*
X898948Y164820D01*
X899595Y164388D01*
X901213Y164710D01*
X901645Y165356D01*
X903264Y165678D01*
X903910Y165246D01*
X905529Y165568D01*
X905961Y166214D01*
X907579Y166536D01*
X908226Y166104D01*
X909844Y166425D01*
X910277Y167072D01*
X922512Y169504D01*
X931505D01*
X935442Y173441D01*
X948370D01*
G02X949978Y172775I0J-2274D01*
G01X950224Y172283D01*
G02X949978Y171545I-492J-246D01*
G01X947047Y170079D01*
G01X521850Y77756D02*
Y76137D01*
G03X521996Y75784I500J0D01*
G01X522058Y75722D01*
G03X522411Y75576I353J354D01*
G01X524055D01*
G03X524408Y75722I0J500D01*
G01X524672Y75986D01*
G03X524818Y76339I-354J353D01*
G01Y122360D01*
X533317Y135262D01*
X533316D01*
X533317Y135263D01*
X533442Y135453D01*
Y135454D01*
X579218Y166328D01*
X639577Y178289D01*
X761279Y154631D01*
X923765Y186402D01*
X931398D01*
X935335Y190339D01*
X948369D01*
G02X950932Y189187I1J-3424D01*
G01X951253Y188545D01*
G03X951991Y188299I492J246D01*
G01X954921Y189764D01*
G01X521850Y72245D02*
Y73864D01*
G02X521996Y74217I500J0D01*
G01X522058Y74279D01*
G02X522411Y74425I353J-354D01*
G01X522412Y74426D01*
X524055D01*
G03X525222Y74908I1J1650D01*
G01X525486Y75173D01*
G03X525968Y76339I-1168J1165D01*
G01Y122015D01*
X534278Y134630D01*
X579669Y165245D01*
X639579Y177117D01*
X761280Y153459D01*
X880583Y176786D01*
X881228Y176352D01*
X882848Y176669D01*
X883282Y177314D01*
X884901Y177631D01*
X885547Y177196D01*
X887166Y177513D01*
X887600Y178158D01*
X889220Y178475D01*
X889865Y178041D01*
X891484Y178357D01*
X891918Y179003D01*
X923877Y185252D01*
X931875D01*
X935812Y189189D01*
X948370D01*
G02X949978Y188523I0J-2274D01*
G01X950224Y188031D01*
G02X949978Y187293I-492J-246D01*
G01X947047Y185827D01*
G01X514764Y73819D02*
Y72200D01*
G03X514910Y71847I500J0D01*
G01X514972Y71785D01*
G03X515325Y71639I353J354D01*
G01X516969D01*
G03X517322Y71785I0J500D01*
G01X517586Y72049D01*
G03X517732Y72402I-354J353D01*
G01Y124818D01*
X525271Y136264D01*
X550105Y153027D01*
Y153026D01*
X574943Y169792D01*
X639854Y182654D01*
X714082Y168228D01*
X918998Y202150D01*
X930796D01*
X934733Y206087D01*
X948369D01*
G02X950932Y204935I1J-3424D01*
G01X951253Y204293D01*
G03X951991Y204047I492J246D01*
G01X954921Y205512D01*
G01X514764Y68307D02*
Y69987D01*
G02X514868Y70238I355J0D01*
G01X514972Y70342D01*
G02X515325Y70488I353J-354D01*
G01X515326Y70489D01*
X516969D01*
G03X518136Y70971I1J1650D01*
G01X518400Y71236D01*
G03X518882Y72402I-1168J1165D01*
G01Y124473D01*
X522494Y129955D01*
Y129956D01*
X526105Y135439D01*
X575394Y168708D01*
X639856Y181482D01*
X714066Y167059D01*
X891669Y196460D01*
X892301Y196007D01*
X893929Y196277D01*
X894382Y196909D01*
X896010Y197179D01*
X896642Y196726D01*
X898270Y196995D01*
X898723Y197628D01*
X900351Y197897D01*
X900983Y197444D01*
X902611Y197714D01*
X903064Y198346D01*
X919093Y201000D01*
X931273D01*
X935210Y204937D01*
X948370D01*
G02X949978Y204271I0J-2274D01*
G01X950224Y203779D01*
G02X949978Y203041I-492J-246D01*
G01X947047Y201575D01*
G01X564370Y77756D02*
Y76338D01*
G03X565133Y75575I763J0D01*
G01X569350D01*
X734609Y108409D01*
X844946Y85298D01*
X917884Y99788D01*
X930724D01*
X934661Y103725D01*
X948440D01*
X952377Y107662D01*
X959919D01*
X970106Y117849D01*
X982435Y136133D01*
X999831Y225663D01*
X977910Y338455D01*
X963847Y359551D01*
X927452Y388818D01*
X924358Y393582D01*
X884968Y571353D01*
X894161Y611965D01*
X923533Y657198D01*
X923534Y657199D01*
X927207Y660027D01*
X927934D01*
X927938Y660023D01*
X931023D01*
X934960Y663960D01*
X948369D01*
G02X950932Y662808I1J-3424D01*
G01X951253Y662166D01*
G03X951991Y661920I492J246D01*
G01X954921Y663385D01*
G01X564370Y72245D02*
Y73662D01*
G02X565133Y74425I763J0D01*
G01X569472D01*
X569474Y74427D01*
X734603Y107235D01*
X844940Y84124D01*
X917998Y98638D01*
X931201D01*
X935138Y102575D01*
X948917D01*
X952854Y106512D01*
X960396D01*
X970998Y117114D01*
X983520Y135684D01*
X1001003Y225663D01*
X978995Y338901D01*
X964706Y360336D01*
X928317Y389599D01*
X925436Y394034D01*
X886147Y571350D01*
X895238Y611510D01*
X916601Y644409D01*
X917362Y644571D01*
X918260Y645954D01*
X918099Y646715D01*
X918997Y648099D01*
X919758Y648261D01*
X920657Y649645D01*
X920495Y650405D01*
X921393Y651789D01*
X922128Y651945D01*
X923047Y653361D01*
X922891Y654096D01*
X924392Y656407D01*
X924792Y656716D01*
X927594Y658873D01*
X931500D01*
X935437Y662810D01*
X948370D01*
G02X949978Y662144I0J-2274D01*
G01X950224Y661652D01*
G02X949978Y660914I-492J-246D01*
G01X947047Y659448D01*
G01X557283Y73819D02*
Y72200D01*
G03X557429Y71847I500J0D01*
G01X557491Y71785D01*
G03X557844Y71639I353J354D01*
G01X559488D01*
G03X559841Y71785I0J500D01*
G01X560105Y72049D01*
G03X560251Y72402I-354J353D01*
G01Y124881D01*
X561460Y126718D01*
X562202Y127218D01*
X562942Y127716D01*
X626864Y140406D01*
X856836Y95351D01*
X918799Y107662D01*
X930724D01*
X934661Y111599D01*
X948440D01*
X952377Y115536D01*
X958176D01*
X963420Y120780D01*
X977137Y141120D01*
X993525Y225455D01*
X971251Y340072D01*
X961357Y354739D01*
X926181Y383026D01*
X922674Y388423D01*
X917088Y397025D01*
X897478Y484179D01*
X877858Y571386D01*
X888539Y618563D01*
X924459Y673656D01*
X927203Y675771D01*
X931019D01*
X934956Y679708D01*
X948369D01*
G02X950932Y678556I1J-3424D01*
G01X951253Y677914D01*
G03X951991Y677668I492J246D01*
G01X954921Y679133D01*
G01X557283Y68307D02*
Y69927D01*
G02X557429Y70280I500J0D01*
G01X557491Y70342D01*
G02X557844Y70488I353J-354D01*
G01X557845Y70489D01*
X559488D01*
G03X560655Y70971I1J1650D01*
G01X560919Y71236D01*
G03X561401Y72402I-1168J1165D01*
G01Y124536D01*
X562294Y125893D01*
X563393Y126632D01*
Y126633D01*
X626865Y139233D01*
X856838Y94178D01*
X918913Y106512D01*
X931201D01*
X935138Y110449D01*
X948917D01*
X952854Y114386D01*
X958653D01*
X964312Y120045D01*
X978222Y140671D01*
X994697Y225455D01*
X972336Y340521D01*
X962214Y355527D01*
X927045Y383807D01*
X923639Y389050D01*
X918165Y397479D01*
X879037Y571385D01*
X889616Y618107D01*
X916570Y659450D01*
X917331Y659611D01*
X918232Y660993D01*
X918072Y661754D01*
X918973Y663136D01*
X919734Y663296D01*
X920636Y664678D01*
X920475Y665439D01*
X921376Y666821D01*
X922138Y666982D01*
X923039Y668364D01*
X922878Y669125D01*
X925316Y672864D01*
X927595Y674621D01*
X931496D01*
X935433Y678558D01*
X948370D01*
G02X949978Y677892I0J-2274D01*
G01X950224Y677400D01*
G02X949978Y676662I-492J-246D01*
G01X947047Y675196D01*
G01X826772Y1630709D02*
Y1632056D01*
G03X825938Y1632890I-834J0D01*
G01X821974D01*
X817314Y1628230D01*
X799015Y1547271D01*
X819701Y1453918D01*
G02Y1453678I-537J-120D01*
G01X806369Y1394763D01*
X793009Y1335724D01*
X1006393Y632484D01*
X1007079Y632118D01*
X1007559Y630539D01*
X1007192Y629853D01*
X1007671Y628274D01*
X1008357Y627907D01*
X1008836Y626328D01*
X1008469Y625642D01*
X1008948Y624063D01*
X1009634Y623696D01*
X1010113Y622118D01*
X1009747Y621432D01*
X1015554Y602293D01*
X1016240Y601927D01*
X1016719Y600348D01*
X1016352Y599662D01*
X1016831Y598083D01*
X1017517Y597716D01*
X1017997Y596137D01*
X1017630Y595451D01*
X1018109Y593872D01*
X1018795Y593506D01*
X1019274Y591927D01*
X1018907Y591241D01*
X1019387Y589662D01*
X1020073Y589295D01*
X1020552Y587716D01*
X1020185Y587030D01*
X1025992Y567892D01*
X1026678Y567525D01*
X1027157Y565946D01*
X1026790Y565260D01*
X1027266Y563693D01*
X1027270Y563681D01*
X1027956Y563315D01*
X1028435Y561736D01*
X1028068Y561050D01*
X1028547Y559471D01*
X1029233Y559104D01*
X1029712Y557525D01*
X1029346Y556839D01*
X1029825Y555261D01*
X1030511Y554894D01*
X1030990Y553315D01*
X1030623Y552629D01*
X1036430Y533491D01*
X1037116Y533124D01*
X1037595Y531545D01*
X1037229Y530859D01*
X1037708Y529280D01*
X1038394Y528914D01*
X1038873Y527335D01*
X1038506Y526649D01*
X1038985Y525070D01*
X1039671Y524703D01*
X1040150Y523124D01*
X1039784Y522438D01*
X1040263Y520859D01*
X1040949Y520493D01*
X1041428Y518914D01*
X1041061Y518228D01*
X1042179Y514544D01*
X1043097Y513173D01*
X1043860Y513022D01*
X1044778Y511651D01*
X1044627Y510888D01*
X1045545Y509517D01*
X1046308Y509366D01*
X1047226Y507995D01*
X1047075Y507232D01*
X1047993Y505861D01*
X1048756Y505710D01*
X1049674Y504339D01*
X1049523Y503576D01*
X1050441Y502205D01*
X1051204Y502054D01*
X1052122Y500683D01*
X1051971Y499920D01*
X1063099Y483301D01*
X1063862Y483150D01*
X1064780Y481779D01*
X1064629Y481016D01*
X1065547Y479645D01*
X1066310Y479494D01*
X1067228Y478123D01*
X1067077Y477360D01*
X1067995Y475989D01*
X1068758Y475838D01*
X1069676Y474467D01*
X1069525Y473704D01*
X1093464Y437952D01*
X1101953Y429463D01*
Y421835D01*
X1103922Y419866D01*
X1117447D01*
X1121384Y415929D01*
X1124424D01*
X1127586Y419091D01*
Y460214D01*
X1125777Y462023D01*
X1121023D01*
X1119115Y460115D01*
G03X1119033Y458022I1090J-1091D01*
G03X1119115Y457934I1169J1007D01*
G01X1119116Y457933D01*
X1119362Y457441D01*
G03X1120100Y457195I492J246D01*
G01X1123031Y458661D01*
G01X826772Y1636221D02*
Y1634874D01*
G02X825938Y1634040I-834J0D01*
G01X821497D01*
X816265Y1628808D01*
X797836Y1547273D01*
X818549Y1453801D01*
X791820Y1335681D01*
X1007846Y623730D01*
X1007847Y623727D01*
X1015729Y597750D01*
X1015730Y597747D01*
X1017007Y593539D01*
X1017008Y593536D01*
X1024890Y567559D01*
X1024891Y567556D01*
X1026164Y563360D01*
X1026169Y563345D01*
X1028723Y554928D01*
X1028724Y554925D01*
X1041128Y514046D01*
X1053900Y494971D01*
X1082710Y451944D01*
X1092570Y437218D01*
X1100803Y428986D01*
Y421358D01*
X1103445Y418716D01*
X1116970D01*
X1120907Y414779D01*
X1124901D01*
X1128736Y418614D01*
Y460691D01*
X1126254Y463173D01*
X1120546D01*
X1119033Y461660D01*
X1119032D01*
X1118301Y460929D01*
G03X1118159Y457275I1904J-1904D01*
G01X1118333Y456927D01*
G02X1118087Y456189I-492J-246D01*
G01X1115157Y454724D01*
G01X833859Y1640945D02*
Y1642421D01*
G03X833713Y1642774I-500J0D01*
G01X833507Y1642980D01*
G03X833154Y1643126I-353J-354D01*
G01X831580D01*
G03X831227Y1642980I0J-500D01*
G01X831037Y1642790D01*
G03X830891Y1642437I354J-353D01*
G01Y1592354D01*
X815622Y1524868D01*
X831676Y1452394D01*
X805878Y1338399D01*
X1046648Y544838D01*
X1076446Y498955D01*
X1077206Y498793D01*
X1078105Y497409D01*
X1077943Y496648D01*
X1078842Y495264D01*
X1079603Y495103D01*
X1080501Y493719D01*
X1080340Y492958D01*
X1081238Y491574D01*
X1081999Y491413D01*
X1082898Y490029D01*
X1082736Y489268D01*
X1083635Y487884D01*
X1084396Y487722D01*
X1085294Y486339D01*
X1085133Y485578D01*
X1086031Y484194D01*
X1086792Y484032D01*
X1087691Y482648D01*
X1087529Y481888D01*
X1093489Y472710D01*
X1096048Y471047D01*
X1099508D01*
X1103445Y474984D01*
X1116479D01*
G02X1119042Y473832I1J-3424D01*
G01X1119363Y473190D01*
G03X1120101Y472944I492J246D01*
G01X1123031Y474409D01*
G01X833859Y1646457D02*
Y1644983D01*
G02X833713Y1644630I-500J0D01*
G01X833505Y1644422D01*
G02X833152Y1644276I-353J354D01*
G01X831580D01*
G03X830414Y1643794I-1J-1650D01*
G01X830223Y1643604D01*
G03X829741Y1642437I1168J-1166D01*
G01Y1592544D01*
G02X829727Y1592423I-550J2D01*
G01X814470Y1524991D01*
G03Y1524751I537J-120D01*
G01X830497Y1452397D01*
X804689Y1338356D01*
X864970Y1139674D01*
X1045594Y544348D01*
X1092657Y471878D01*
X1095707Y469897D01*
X1099985D01*
X1103922Y473834D01*
X1116480D01*
G02X1118088Y473168I0J-2274D01*
G01X1118334Y472676D01*
G02X1118088Y471938I-492J-246D01*
G01X1115157Y470472D01*
G01X826772Y1616536D02*
Y1618012D01*
G03X826626Y1618365I-500J0D01*
G01X826420Y1618571D01*
G03X826067Y1618717I-353J-354D01*
G01X824382D01*
G03X824191Y1618679I0J-499D01*
G01X823923Y1618568D01*
G03X823761Y1618460I191J-462D01*
G01X820455Y1615154D01*
X805046Y1547071D01*
X825743Y1453671D01*
X799440Y1337434D01*
X1044617Y529413D01*
X1045303Y529047D01*
X1045782Y527468D01*
X1045416Y526782D01*
X1045895Y525203D01*
X1046581Y524836D01*
X1047060Y523257D01*
X1046693Y522571D01*
X1047172Y520992D01*
X1047858Y520626D01*
X1048338Y519047D01*
X1047971Y518361D01*
X1047973Y518355D01*
X1048450Y516782D01*
X1063214Y494049D01*
X1063975Y493887D01*
X1064874Y492503D01*
X1064712Y491742D01*
X1065611Y490359D01*
X1066372Y490197D01*
X1067270Y488813D01*
X1067109Y488052D01*
X1068007Y486669D01*
X1068768Y486507D01*
X1069667Y485123D01*
X1069505Y484362D01*
X1070404Y482978D01*
X1071165Y482817D01*
X1072063Y481433D01*
X1071902Y480672D01*
X1082795Y463899D01*
X1083556Y463737D01*
X1084455Y462354D01*
X1084293Y461593D01*
X1085192Y460209D01*
X1085952Y460047D01*
X1086851Y458664D01*
X1086689Y457903D01*
X1087588Y456519D01*
X1088349Y456357D01*
X1089248Y454974D01*
X1089086Y454213D01*
X1089985Y452829D01*
X1090745Y452667D01*
X1091644Y451283D01*
X1091482Y450523D01*
X1092674Y448688D01*
X1094154Y447727D01*
X1095459Y447450D01*
X1098321D01*
G03X1100461Y448271I-3J3206D01*
G01X1100618Y448583D01*
G03X1100372Y449321I-492J246D01*
G01X1097441Y450787D01*
G01X826772Y1622048D02*
Y1620574D01*
G02X826626Y1620221I-500J0D01*
G01X826418Y1620013D01*
G02X826065Y1619867I-353J354D01*
G01X824382D01*
G03X823751Y1619742I-1J-1649D01*
G01X823483Y1619631D01*
G03X822948Y1619274I631J-1525D01*
G01X819406Y1615733D01*
X803867Y1547074D01*
X824564Y1453674D01*
X798251Y1337391D01*
X1044793Y524870D01*
X1044794Y524867D01*
X1046870Y518025D01*
X1046871Y518022D01*
X1047396Y516292D01*
X1069597Y482109D01*
X1091842Y447856D01*
X1093707Y446646D01*
X1095338Y446300D01*
X1098320D01*
G03X1101401Y447576I0J4357D01*
G01X1101647Y448069D01*
G02X1102385Y448315I492J-246D01*
G01X1105315Y446850D01*
G01X840945Y1630709D02*
Y1632056D01*
G03X840111Y1632890I-834J0D01*
G01X839060D01*
G03X837977Y1631807I0J-1083D01*
G01Y1591889D01*
X822416Y1523104D01*
X838173Y1451993D01*
X813271Y1341904D01*
X1054271Y547573D01*
X1079472Y508768D01*
X1080233Y508606D01*
X1081132Y507222D01*
X1080970Y506461D01*
X1081869Y505078D01*
X1082630Y504916D01*
X1083528Y503532D01*
X1083367Y502771D01*
X1084265Y501388D01*
X1085026Y501226D01*
X1085925Y499842D01*
X1085763Y499081D01*
X1086662Y497697D01*
X1087423Y497536D01*
X1088321Y496152D01*
X1088160Y495391D01*
X1089058Y494007D01*
X1089819Y493846D01*
X1090718Y492462D01*
X1090556Y491701D01*
X1092183Y489196D01*
X1095881Y486795D01*
X1099459D01*
X1103396Y490732D01*
X1116479D01*
G02X1119042Y489580I1J-3424D01*
G01X1119363Y488938D01*
G03X1120101Y488692I492J246D01*
G01X1123031Y490157D01*
G01X840945Y1636221D02*
Y1634874D01*
G02X840111Y1634040I-834J0D01*
G01X839060D01*
G03X836827Y1631807I0J-2233D01*
G01Y1592079D01*
G02X836813Y1591958I-550J2D01*
G01X821264Y1523227D01*
G03Y1522987I537J-120D01*
G01X829171Y1487300D01*
X836994Y1451996D01*
X812082Y1341861D01*
X1053217Y547083D01*
X1062784Y532352D01*
X1062783D01*
X1091351Y488364D01*
X1095540Y485645D01*
X1099936D01*
X1103873Y489582D01*
X1116480D01*
G02X1118088Y488916I0J-2274D01*
G01X1118334Y488424D01*
G02X1118088Y487686I-492J-246D01*
G01X1115157Y486220D01*
G01X848032Y1640945D02*
Y1642421D01*
G03X847886Y1642774I-500J0D01*
G01X847680Y1642980D01*
G03X847327Y1643126I-353J-354D01*
G01X845618D01*
G03X845265Y1642980I0J-500D01*
G01X845210Y1642925D01*
G03X845064Y1642572I354J-353D01*
G01Y1598115D01*
X829022Y1527225D01*
X844142Y1451558D01*
X819714Y1343568D01*
X1058034Y558076D01*
X1079439Y525118D01*
X1080200Y524956D01*
X1081099Y523572D01*
X1080937Y522812D01*
X1081836Y521428D01*
X1082597Y521266D01*
X1083496Y519882D01*
X1083334Y519122D01*
X1084233Y517738D01*
X1084993Y517576D01*
X1085892Y516192D01*
X1085730Y515432D01*
X1086629Y514048D01*
X1087390Y513886D01*
X1088289Y512502D01*
X1088127Y511742D01*
X1089026Y510358D01*
X1089787Y510196D01*
X1090685Y508812D01*
X1090524Y508052D01*
X1092731Y504653D01*
X1095979Y502543D01*
X1099508D01*
X1103445Y506480D01*
X1116479D01*
G02X1119042Y505328I1J-3424D01*
G01X1119363Y504686D01*
G03X1120101Y504440I492J246D01*
G01X1123031Y505905D01*
G01X848032Y1646457D02*
Y1644983D01*
G02X847886Y1644630I-500J0D01*
G01X847678Y1644422D01*
G02X847325Y1644276I-353J354D01*
G01X845618D01*
G03X844452Y1643794I-1J-1650D01*
G01X844396Y1643739D01*
G03X843914Y1642572I1168J-1166D01*
G01Y1598305D01*
G02X843900Y1598184I-550J2D01*
G01X827872Y1527354D01*
G03X827869Y1527125I536J-122D01*
G01X835454Y1489166D01*
X842966Y1451573D01*
X818525Y1343525D01*
X818612Y1343235D01*
X818613D01*
X1056980Y557586D01*
X1091899Y503821D01*
X1095638Y501393D01*
X1099985D01*
X1103922Y505330D01*
X1116480D01*
G02X1118088Y504664I0J-2274D01*
G01X1118334Y504172D01*
G02X1118088Y503434I-492J-246D01*
G01X1115157Y501968D01*
G01X855118Y1636221D02*
Y1634874D01*
G02X854284Y1634040I-834J0D01*
G01X853233D01*
G03X851000Y1631807I0J-2233D01*
G01Y1590967D01*
G02X850986Y1590846I-550J2D01*
G01X835187Y1521009D01*
G03Y1520769I537J-120D01*
G01X842627Y1487145D01*
X849982Y1453903D01*
X825172Y1344255D01*
X1020870Y699244D01*
X1081454Y605956D01*
X1093972Y595881D01*
X1099762D01*
X1103699Y599818D01*
X1116480D01*
G02X1118088Y599152I0J-2274D01*
G01X1118334Y598660D01*
G02X1118088Y597922I-492J-246D01*
G01X1115157Y596456D01*
G01X855118Y1630709D02*
Y1632056D01*
G03X854284Y1632890I-834J0D01*
G01X853233D01*
G03X852150Y1631807I0J-1083D01*
G01Y1590777D01*
X836339Y1520886D01*
X851161Y1453900D01*
X826361Y1344298D01*
X1021924Y699734D01*
X1070119Y625523D01*
X1070935Y625350D01*
X1071834Y623966D01*
X1071660Y623150D01*
X1072559Y621766D01*
X1073375Y621592D01*
X1074274Y620209D01*
X1074100Y619392D01*
X1074999Y618009D01*
X1075815Y617835D01*
X1076714Y616451D01*
X1076540Y615635D01*
X1077439Y614251D01*
X1078255Y614078D01*
X1079154Y612694D01*
X1078980Y611878D01*
X1079879Y610494D01*
X1080695Y610321D01*
X1081594Y608937D01*
X1081420Y608121D01*
X1082319Y606737D01*
X1094378Y597031D01*
X1099285D01*
X1103222Y600968D01*
X1116479D01*
G02X1119042Y599816I1J-3424D01*
G01X1119363Y599174D01*
G03X1120101Y598928I492J246D01*
G01X1123031Y600393D01*
G01X862205Y1640945D02*
Y1642421D01*
G03X862059Y1642774I-500J0D01*
G01X861853Y1642980D01*
G03X861500Y1643126I-353J-354D01*
G01X860784D01*
G03X859237Y1641579I0J-1547D01*
G01Y1599679D01*
X842623Y1526256D01*
X857452Y1453406D01*
X833040Y1345456D01*
X1027507Y704501D01*
X1066705Y644140D01*
X1067521Y643967D01*
X1068420Y642583D01*
X1068246Y641767D01*
X1069145Y640383D01*
X1069961Y640209D01*
X1070860Y638826D01*
X1070686Y638010D01*
X1071585Y636626D01*
X1072401Y636452D01*
X1073300Y635068D01*
X1073126Y634252D01*
X1074025Y632868D01*
X1074841Y632695D01*
X1075740Y631311D01*
X1075566Y630495D01*
X1076465Y629111D01*
X1077281Y628938D01*
X1078180Y627554D01*
X1078006Y626738D01*
X1078905Y625354D01*
X1094534Y612779D01*
X1099471D01*
X1103408Y616716D01*
X1116479D01*
G02X1119042Y615564I1J-3424D01*
G01X1119363Y614922D01*
G03X1120101Y614676I492J246D01*
G01X1123031Y616141D01*
G01X862205Y1646457D02*
Y1644983D01*
G02X862059Y1644630I-500J0D01*
G01X861851Y1644422D01*
G02X861498Y1644276I-353J354D01*
G01X860784D01*
G03X858087Y1641579I0J-2697D01*
G01Y1599869D01*
G02X858073Y1599748I-550J2D01*
G01X841472Y1526384D01*
G03X841470Y1526153I537J-120D01*
G01X856275Y1453419D01*
X831851Y1345413D01*
X1026453Y704011D01*
X1078040Y624573D01*
X1094128Y611629D01*
X1099948D01*
X1103885Y615566D01*
X1116480D01*
G02X1118088Y614900I0J-2274D01*
G01X1118334Y614408D01*
G02X1118088Y613670I-492J-246D01*
G01X1115157Y612204D01*
G01X869292Y1636221D02*
Y1634874D01*
G02X868458Y1634040I-834J0D01*
G01X867407D01*
G03X865174Y1631807I0J-2233D01*
G01Y1595930D01*
G02X865160Y1595809I-550J2D01*
G01X848676Y1522954D01*
G03Y1522714I537J-120D01*
G01X862910Y1458390D01*
X837977Y1348125D01*
X1031629Y709853D01*
X1074558Y643747D01*
X1074552Y643740D01*
X1094905Y627377D01*
X1099404D01*
X1103341Y631314D01*
X1116480D01*
G02X1118088Y630648I0J-2274D01*
G01X1118334Y630156D01*
G02X1118088Y629418I-492J-246D01*
G01X1115157Y627952D01*
G01X869292Y1630709D02*
Y1632056D01*
G03X868458Y1632890I-834J0D01*
G01X867407D01*
G03X866324Y1631807I0J-1083D01*
G01Y1595740D01*
X849828Y1522831D01*
X864089Y1458387D01*
X839166Y1348168D01*
X1032683Y710343D01*
X1075423Y644528D01*
X1075418Y644521D01*
X1077853Y642563D01*
X1078683Y642653D01*
X1079968Y641619D01*
X1080059Y640790D01*
X1081344Y639756D01*
X1082174Y639846D01*
X1083460Y638812D01*
X1083550Y637983D01*
X1084836Y636949D01*
X1085665Y637039D01*
X1086951Y636005D01*
X1087041Y635175D01*
X1088327Y634141D01*
X1089157Y634232D01*
X1090443Y633198D01*
X1090533Y632368D01*
X1091819Y631334D01*
X1092648Y631424D01*
X1093934Y630390D01*
X1094024Y629561D01*
X1095310Y628527D01*
X1098927D01*
X1102864Y632464D01*
X1116479D01*
G02X1119042Y631312I1J-3424D01*
G01X1119363Y630670D01*
G03X1120101Y630424I492J246D01*
G01X1123031Y631889D01*
G01X876378Y1640945D02*
Y1642421D01*
G03X876232Y1642774I-500J0D01*
G01X876026Y1642980D01*
G03X875673Y1643126I-353J-354D01*
G01X874858D01*
G03X873410Y1641678I0J-1448D01*
G01Y1596287D01*
X856935Y1523461D01*
X856934Y1523459D01*
X870097Y1458508D01*
X845549Y1350038D01*
X1036817Y719625D01*
X1075948Y659375D01*
X1075950Y659376D01*
X1077274Y658311D01*
X1078104Y658401D01*
X1079389Y657367D01*
X1079480Y656538D01*
X1080765Y655504D01*
X1081595Y655594D01*
X1082881Y654560D01*
X1082971Y653731D01*
X1084257Y652697D01*
X1085086Y652787D01*
X1086372Y651753D01*
X1086462Y650923D01*
X1087748Y649889D01*
X1088578Y649980D01*
X1089864Y648946D01*
X1089954Y648116D01*
X1091240Y647082D01*
X1092069Y647172D01*
X1093355Y646138D01*
X1093445Y645309D01*
X1094731Y644275D01*
X1099508D01*
X1103445Y648212D01*
X1116479D01*
G02X1119042Y647060I1J-3424D01*
G01X1119363Y646418D01*
G03X1120101Y646172I492J246D01*
G01X1123031Y647637D01*
G01X876378Y1646457D02*
Y1644983D01*
G02X876232Y1644630I-500J0D01*
G01X876024Y1644422D01*
G02X875671Y1644276I-353J354D01*
G01X874858D01*
G03X872260Y1641678I0J-2598D01*
G01Y1596477D01*
G02X872246Y1596356I-550J2D01*
G01X855784Y1523589D01*
G03X855781Y1523358I536J-122D01*
G01X868920Y1458521D01*
X844360Y1349995D01*
X1035763Y719135D01*
X1075084Y658592D01*
X1075086Y658594D01*
X1094326Y643125D01*
X1099985D01*
X1103922Y647062D01*
X1116480D01*
G02X1118088Y646396I0J-2274D01*
G01X1118334Y645904D01*
G02X1118088Y645166I-492J-246D01*
G01X1115157Y643700D01*
G01X1504528Y77756D02*
Y76137D01*
G03X1504674Y75784I500J0D01*
G01X1504736Y75722D01*
G03X1505089Y75576I353J354D01*
G01X1506733D01*
G03X1507086Y75722I0J500D01*
G01X1507350Y75986D01*
G03X1507496Y76339I-354J353D01*
G01Y128772D01*
X1469844Y187820D01*
X1353269Y269595D01*
Y269596D01*
X1236694Y351372D01*
X1169976Y366007D01*
X1169321Y365588D01*
X1167709Y365941D01*
X1167290Y366596D01*
X1165678Y366950D01*
X1165023Y366531D01*
X1163411Y366884D01*
X1162992Y367539D01*
X1130331Y374704D01*
X1129676Y374285D01*
X1128065Y374638D01*
X1127645Y375293D01*
X1126034Y375647D01*
X1125378Y375227D01*
X1123767Y375581D01*
X1123347Y376236D01*
X1121736Y376590D01*
X1121081Y376170D01*
X1119469Y376524D01*
X1119050Y377179D01*
X1115972Y377854D01*
X1093857Y372951D01*
X1078675Y362902D01*
X1064794Y341928D01*
X1064437Y340317D01*
X1064885Y339613D01*
X1064529Y338002D01*
X1063825Y337554D01*
X1063468Y335943D01*
X1063916Y335239D01*
X1063559Y333629D01*
X1062856Y333180D01*
X1062499Y331569D01*
X1062947Y330866D01*
X1062590Y329255D01*
X1061887Y328806D01*
X1061530Y327195D01*
X1061978Y326492D01*
X1061621Y324881D01*
X1060918Y324432D01*
X1051671Y282698D01*
X1052035Y281089D01*
X1052693Y280674D01*
X1053057Y279064D01*
X1052642Y278406D01*
X1053006Y276797D01*
X1053664Y276382D01*
X1054028Y274773D01*
X1053613Y274115D01*
X1053977Y272506D01*
X1054635Y272091D01*
X1054999Y270481D01*
X1054584Y269823D01*
X1054948Y268214D01*
X1055606Y267799D01*
X1055970Y266190D01*
X1055555Y265532D01*
X1074775Y180576D01*
X1089766Y157930D01*
X1094513Y154906D01*
X1099508D01*
X1103445Y158843D01*
X1116479D01*
G02X1119042Y157691I1J-3424D01*
G01X1119363Y157049D01*
G03X1120101Y156803I492J246D01*
G01X1123031Y158268D01*
G01X1115157Y154331D02*
X1118088Y155797D01*
G03X1118334Y156535I-246J492D01*
G01X1118088Y157027D01*
G03X1116480Y157693I-1608J-1608D01*
G01X1103922D01*
X1099985Y153756D01*
X1094177D01*
X1088942Y157091D01*
X1073699Y180116D01*
X1050492Y282695D01*
X1063717Y342385D01*
X1077845Y363732D01*
X1093400Y374028D01*
X1115971Y379032D01*
X1237166Y352446D01*
X1470691Y188631D01*
X1508646Y129108D01*
Y76339D01*
G02X1508164Y75173I-1650J-1D01*
G01X1507900Y74908D01*
G02X1506733Y74426I-1166J1168D01*
G01X1505090D01*
X1505089Y74425D01*
G03X1504736Y74279I0J-500D01*
G01X1504674Y74217D01*
G03X1504528Y73864I354J-353D01*
G01Y72245D01*
G01X1123031Y174016D02*
X1120101Y172551D01*
G02X1119363Y172797I-246J492D01*
G01X1119042Y173439D01*
G03X1116479Y174591I-2562J-2272D01*
G01X1103191D01*
X1099254Y170654D01*
X1094767D01*
X1090566Y173330D01*
X1080557Y188450D01*
X1063627Y263265D01*
X1064042Y263923D01*
X1063678Y265532D01*
X1063020Y265947D01*
X1062656Y267556D01*
X1063071Y268214D01*
X1062707Y269824D01*
X1062049Y270239D01*
X1061685Y271848D01*
X1062100Y272506D01*
X1061736Y274115D01*
X1061078Y274530D01*
X1060714Y276139D01*
X1061129Y276797D01*
X1060765Y278407D01*
X1060107Y278822D01*
X1059743Y280431D01*
X1069965Y326551D01*
X1070668Y326999D01*
X1071025Y328610D01*
X1070577Y329313D01*
X1070934Y330924D01*
X1071638Y331373D01*
X1071995Y332984D01*
X1071546Y333687D01*
X1071903Y335298D01*
X1072607Y335747D01*
X1072964Y337358D01*
X1072516Y338061D01*
X1072873Y339672D01*
X1073576Y340120D01*
X1073933Y341731D01*
X1073485Y342435D01*
X1073842Y344046D01*
X1082504Y357133D01*
X1098329Y367610D01*
Y367611D01*
X1115165Y371343D01*
X1118353Y370641D01*
X1118772Y369986D01*
X1120384Y369631D01*
X1121039Y370050D01*
X1122650Y369695D01*
X1123069Y369040D01*
X1124681Y368685D01*
X1125336Y369104D01*
X1126947Y368749D01*
X1127366Y368094D01*
X1128978Y367739D01*
X1129633Y368158D01*
X1163242Y360759D01*
X1163661Y360104D01*
X1165272Y359749D01*
X1165928Y360168D01*
X1167539Y359813D01*
X1167958Y359158D01*
X1169570Y358803D01*
X1170225Y359222D01*
X1231464Y345741D01*
X1466806Y180652D01*
X1500409Y127945D01*
Y72402D01*
G02X1500263Y72049I-500J0D01*
G01X1499999Y71785D01*
G02X1499646Y71639I-353J354D01*
G01X1498002D01*
G02X1497649Y71785I0J500D01*
G01X1497587Y71847D01*
G02X1497441Y72200I354J353D01*
G01Y73819D01*
G01X1115157Y170079D02*
X1118088Y171545D01*
G03X1118334Y172283I-246J492D01*
G01X1118088Y172775D01*
G03X1116480Y173441I-1608J-1608D01*
G01X1103668D01*
X1099731Y169504D01*
X1094431D01*
X1089742Y172491D01*
X1079481Y187990D01*
X1058564Y280428D01*
X1072765Y344503D01*
X1081674Y357963D01*
X1097872Y368688D01*
X1115164Y372521D01*
X1231936Y346815D01*
X1467653Y181463D01*
X1501559Y128281D01*
Y72402D01*
G02X1501077Y71236I-1650J-1D01*
G01X1500813Y70971D01*
G02X1499646Y70489I-1166J1168D01*
G01X1498003D01*
X1498002Y70488D01*
G03X1497649Y70342I0J-500D01*
G01X1497587Y70280D01*
G03X1497441Y69927I354J-353D01*
G01Y68307D01*
G01X1123031Y189764D02*
X1120101Y188299D01*
G02X1119363Y188545I-246J492D01*
G01X1119042Y189187D01*
G03X1116479Y190339I-2562J-2272D01*
G01X1103239D01*
X1099302Y186402D01*
X1095566D01*
X1094265Y186667D01*
X1090283Y189305D01*
X1085232Y196939D01*
X1071053Y259585D01*
X1071468Y260243D01*
X1071104Y261852D01*
X1070446Y262267D01*
X1070084Y263869D01*
X1070082Y263877D01*
X1070497Y264534D01*
X1070133Y266144D01*
X1069475Y266559D01*
X1069111Y268168D01*
X1069526Y268826D01*
X1069161Y270435D01*
X1068504Y270850D01*
X1068503Y270854D01*
X1068139Y272460D01*
X1068554Y273117D01*
X1068190Y274727D01*
X1067532Y275142D01*
X1067168Y276751D01*
X1078001Y325665D01*
X1078705Y326113D01*
X1079061Y327724D01*
X1078613Y328428D01*
X1078970Y330039D01*
X1079673Y330487D01*
X1080030Y332098D01*
X1079582Y332802D01*
X1079939Y334413D01*
X1080642Y334861D01*
X1080999Y336472D01*
X1080550Y337176D01*
X1080907Y338787D01*
X1081611Y339235D01*
X1081968Y340846D01*
X1081519Y341550D01*
X1081876Y343161D01*
X1087723Y352012D01*
X1102108Y361537D01*
X1114443Y364271D01*
X1119796Y363091D01*
X1120215Y362436D01*
X1121826Y362081D01*
X1122481Y362499D01*
X1124093Y362144D01*
X1124511Y361489D01*
X1126123Y361133D01*
X1126778Y361552D01*
X1128390Y361197D01*
X1128808Y360542D01*
X1130420Y360186D01*
X1131075Y360605D01*
X1163119Y353542D01*
X1163538Y352887D01*
X1165149Y352531D01*
X1165804Y352950D01*
X1167416Y352595D01*
X1167834Y351940D01*
X1169446Y351584D01*
X1170101Y352003D01*
X1200425Y345319D01*
X1459902Y180015D01*
X1459901D01*
X1476611Y153809D01*
Y153810D01*
X1493322Y127603D01*
Y76339D01*
G02X1493176Y75986I-500J0D01*
G01X1492912Y75722D01*
G02X1492559Y75576I-353J354D01*
G01X1490915D01*
G02X1490562Y75722I0J500D01*
G01X1490500Y75784D01*
G02X1490354Y76137I354J353D01*
G01Y77756D01*
G01X1115157Y185827D02*
X1118088Y187293D01*
G03X1118334Y188031I-246J492D01*
G01X1118088Y188523D01*
G03X1116480Y189189I-1608J-1608D01*
G01X1103716D01*
X1099779Y185252D01*
X1095450D01*
X1093816Y185584D01*
X1089453Y188475D01*
X1084156Y196480D01*
X1065989Y276748D01*
X1080798Y343618D01*
X1086892Y352842D01*
X1101651Y362614D01*
X1114442Y365449D01*
X1200872Y346399D01*
X1460734Y180849D01*
X1494472Y127939D01*
Y76339D01*
G02X1493990Y75173I-1650J-1D01*
G01X1493726Y74908D01*
G02X1492559Y74426I-1166J1168D01*
G01X1490916D01*
X1490915Y74425D01*
G03X1490562Y74279I0J-500D01*
G01X1490500Y74217D01*
G03X1490354Y73864I354J-353D01*
G01Y72245D01*
G01X1123031Y205512D02*
X1120101Y204047D01*
G02X1119363Y204293I-246J492D01*
G01X1119042Y204935D01*
G03X1116479Y206087I-2562J-2272D01*
G01X1103187D01*
X1099250Y202150D01*
X1095287D01*
X1092411Y204053D01*
X1090969Y206231D01*
X1078658Y260629D01*
X1079073Y261287D01*
X1078709Y262896D01*
X1078051Y263311D01*
X1077687Y264921D01*
X1078102Y265578D01*
X1077737Y267188D01*
X1077080Y267603D01*
X1076715Y269212D01*
X1077130Y269870D01*
X1076766Y271479D01*
X1076108Y271894D01*
X1075744Y273504D01*
X1076159Y274161D01*
X1075795Y275771D01*
X1075137Y276186D01*
X1074773Y277795D01*
X1084444Y321446D01*
X1085147Y321895D01*
X1085504Y323506D01*
X1085056Y324209D01*
X1085413Y325820D01*
X1086117Y326269D01*
X1086473Y327880D01*
X1086025Y328583D01*
X1086382Y330194D01*
X1087086Y330643D01*
X1087442Y332253D01*
X1086994Y332957D01*
X1087351Y334568D01*
X1088055Y335016D01*
X1088412Y336627D01*
X1087963Y337331D01*
X1088320Y338942D01*
X1094423Y348164D01*
X1104831Y355052D01*
X1115929Y357512D01*
X1121838Y356211D01*
X1122256Y355556D01*
X1123868Y355201D01*
X1124523Y355620D01*
X1126135Y355265D01*
X1126553Y354610D01*
X1128165Y354255D01*
X1128820Y354674D01*
X1130432Y354319D01*
X1130851Y353664D01*
X1132462Y353309D01*
X1133117Y353728D01*
X1160178Y347770D01*
X1160597Y347115D01*
X1162208Y346760D01*
X1162864Y347179D01*
X1164475Y346824D01*
X1164894Y346169D01*
X1166505Y345814D01*
X1167161Y346233D01*
X1201746Y338619D01*
X1406805Y207979D01*
X1430231Y172585D01*
X1471995Y144241D01*
X1471993Y144240D01*
X1486236Y121903D01*
Y72402D01*
G02X1486090Y72049I-500J0D01*
G01X1485826Y71785D01*
G02X1485473Y71639I-353J354D01*
G01X1483829D01*
G02X1483476Y71785I0J500D01*
G01X1483414Y71847D01*
G02X1483268Y72200I354J353D01*
G01Y73819D01*
G01X1115157Y201575D02*
X1118088Y203041D01*
G03X1118334Y203779I-246J492D01*
G01X1118088Y204271D01*
G03X1116480Y204937I-1608J-1608D01*
G01X1103664D01*
X1099727Y201000D01*
X1094940D01*
X1091581Y203223D01*
X1089893Y205771D01*
X1073594Y277792D01*
X1087243Y339399D01*
X1093593Y348994D01*
X1104374Y356129D01*
X1115928Y358690D01*
X1202193Y339699D01*
X1407423Y208950D01*
X1407629Y208818D01*
X1431065Y173409D01*
X1472835Y145062D01*
X1487386Y122239D01*
Y72402D01*
G02X1486904Y71236I-1650J-1D01*
G01X1486640Y70971D01*
G02X1485473Y70489I-1166J1168D01*
G01X1483830D01*
X1483829Y70488D01*
G03X1483476Y70342I0J-500D01*
G01X1483414Y70280D01*
G03X1483268Y69927I354J-353D01*
G01Y68307D01*
G01X1532874Y77756D02*
Y76137D01*
G03X1533020Y75784I500J0D01*
G01X1533082Y75722D01*
G03X1533435Y75576I353J354D01*
G01X1535079D01*
G03X1535432Y75722I0J500D01*
G01X1535696Y75986D01*
G03X1535842Y76339I-354J353D01*
G01Y128618D01*
X1500400Y179839D01*
X1459240Y276134D01*
X1458305Y277493D01*
X1457540Y277635D01*
X1456604Y278994D01*
X1456746Y279759D01*
X1455810Y281118D01*
X1455045Y281259D01*
X1454110Y282618D01*
X1454251Y283383D01*
X1453316Y284743D01*
X1452551Y284884D01*
X1451616Y286243D01*
X1451757Y287008D01*
X1433364Y313735D01*
X1432599Y313877D01*
X1431664Y315236D01*
X1431805Y316001D01*
X1430870Y317360D01*
X1430105Y317501D01*
X1429170Y318861D01*
X1429311Y319626D01*
X1428376Y320985D01*
X1427611Y321126D01*
X1426675Y322485D01*
X1426817Y323250D01*
X1425882Y324609D01*
X1425117Y324751D01*
X1424181Y326110D01*
X1424323Y326875D01*
X1186962Y671799D01*
X1186197Y671940D01*
X1185262Y673299D01*
X1185403Y674064D01*
X1184468Y675423D01*
X1183703Y675565D01*
X1182767Y676924D01*
X1182909Y677689D01*
X1181974Y679048D01*
X1181209Y679190D01*
X1180273Y680549D01*
X1180415Y681314D01*
X1155328Y717768D01*
X1154507Y717920D01*
X1153572Y719279D01*
X1153724Y720099D01*
X1152788Y721459D01*
X1151968Y721610D01*
X1151032Y722970D01*
X1151184Y723790D01*
X1150249Y725149D01*
X1149428Y725301D01*
X1148493Y726660D01*
X1148644Y727481D01*
X1147709Y728840D01*
X1125518Y747319D01*
X1108541Y752732D01*
X1095580Y748592D01*
X1076368Y733140D01*
X1076367Y733139D01*
X1071220Y713636D01*
X1076784Y687458D01*
X1093314Y662013D01*
X1096376Y660023D01*
X1099223D01*
X1103160Y663960D01*
X1116479D01*
G02X1119042Y662808I1J-3424D01*
G01X1119363Y662166D01*
G03X1120101Y661920I492J246D01*
G01X1123031Y663385D01*
G01X1532874Y72245D02*
Y73864D01*
G02X1533020Y74217I500J0D01*
G01X1533082Y74279D01*
G02X1533435Y74425I353J-354D01*
G01X1533436Y74426D01*
X1535079D01*
G03X1536246Y74908I1J1650D01*
G01X1536510Y75173D01*
G03X1536992Y76339I-1168J1165D01*
G01Y128806D01*
G03X1536894Y129119I-549J0D01*
G01X1519116Y154812D01*
X1511788Y165403D01*
X1501444Y180352D01*
G02X1501390Y180449I451J315D01*
G01X1460253Y276692D01*
X1148567Y729623D01*
X1126082Y748347D01*
X1108541Y753940D01*
X1095026Y749623D01*
X1075352Y733800D01*
X1075351D01*
X1070038Y713665D01*
X1075703Y687009D01*
X1075712Y686996D01*
X1092482Y661181D01*
X1096035Y658873D01*
X1099700D01*
X1103637Y662810D01*
X1116480D01*
G02X1118088Y662144I0J-2274D01*
G01X1118334Y661652D01*
G02X1118088Y660914I-492J-246D01*
G01X1115157Y659448D01*
G01X1525787Y73819D02*
Y72200D01*
G03X1525933Y71847I500J0D01*
G01X1525995Y71785D01*
G03X1526348Y71639I353J354D01*
G01X1527992D01*
G03X1528345Y71785I0J500D01*
G01X1528609Y72049D01*
G03X1528755Y72402I-354J353D01*
G01Y130616D01*
X1497358Y175935D01*
X1461059Y260815D01*
X1242518Y577259D01*
X1241753Y577399D01*
X1240816Y578756D01*
X1240956Y579521D01*
X1240018Y580879D01*
X1239253Y581019D01*
X1238315Y582377D01*
X1238455Y583142D01*
X1214493Y617840D01*
X1213728Y617980D01*
X1212791Y619338D01*
X1212931Y620103D01*
X1211993Y621461D01*
X1211228Y621601D01*
X1210290Y622958D01*
X1210430Y623723D01*
X1209493Y625081D01*
X1208728Y625221D01*
X1207790Y626579D01*
X1207930Y627344D01*
X1185152Y660328D01*
X1184331Y660478D01*
X1183394Y661835D01*
X1183544Y662656D01*
X1182606Y664014D01*
X1181786Y664164D01*
X1180848Y665522D01*
X1180998Y666343D01*
X1180061Y667700D01*
X1179240Y667850D01*
X1178302Y669208D01*
X1178452Y670029D01*
X1177515Y671387D01*
X1176694Y671537D01*
X1175756Y672894D01*
X1175907Y673715D01*
X1149655Y711728D01*
X1148890Y711868D01*
X1147952Y713225D01*
X1148092Y713990D01*
X1147155Y715348D01*
X1146390Y715488D01*
X1145452Y716846D01*
X1145592Y717611D01*
X1144654Y718969D01*
X1143889Y719109D01*
X1142952Y720466D01*
X1143092Y721231D01*
X1142154Y722589D01*
X1141389Y722729D01*
X1140451Y724087D01*
X1140591Y724852D01*
X1137994Y728613D01*
X1121345Y742475D01*
X1108775Y746485D01*
X1097343Y742837D01*
X1082258Y730699D01*
X1078099Y714925D01*
X1083082Y691488D01*
X1091082Y679160D01*
X1095397Y676358D01*
X1096299Y675771D01*
X1099344D01*
X1103281Y679708D01*
X1116479D01*
G02X1119042Y678556I1J-3424D01*
G01X1119363Y677914D01*
G03X1120101Y677668I492J246D01*
G01X1123031Y679133D01*
G01X1525787Y68307D02*
Y69927D01*
G02X1525933Y70280I500J0D01*
G01X1525995Y70342D01*
G02X1526348Y70488I353J-354D01*
G01X1526349Y70489D01*
X1527992D01*
G03X1529159Y70971I1J1650D01*
G01X1529423Y71236D01*
G03X1529905Y72402I-1168J1165D01*
G01Y130976D01*
X1498370Y176494D01*
X1462072Y261374D01*
X1138851Y729396D01*
X1121909Y743503D01*
X1108775Y747693D01*
X1096789Y743868D01*
X1081242Y731358D01*
X1076917Y714954D01*
X1082001Y691041D01*
X1090250Y678328D01*
X1094770Y675393D01*
X1095958Y674621D01*
X1099821D01*
X1103758Y678558D01*
X1116480D01*
G02X1118088Y677892I0J-2274D01*
G01X1118334Y677400D01*
G02X1118088Y676662I-492J-246D01*
G01X1115157Y675196D01*
G01X1518701Y77756D02*
Y76137D01*
G03X1518847Y75784I500J0D01*
G01X1518909Y75722D01*
G03X1519262Y75576I353J354D01*
G01X1520906D01*
G03X1521259Y75722I0J500D01*
G01X1521523Y75986D01*
G03X1521669Y76339I-354J353D01*
G01Y130967D01*
X1490037Y176674D01*
X1458269Y250981D01*
X1236135Y573785D01*
X1235371Y573927D01*
X1234435Y575286D01*
X1234576Y576051D01*
X1233641Y577410D01*
X1232876Y577551D01*
X1231941Y578911D01*
X1232082Y579675D01*
X1207858Y614877D01*
X1207094Y615018D01*
X1206158Y616377D01*
X1206299Y617142D01*
X1205364Y618502D01*
X1204599Y618643D01*
X1203664Y620002D01*
X1203805Y620767D01*
X1202870Y622126D01*
X1202105Y622268D01*
X1201169Y623627D01*
X1201311Y624392D01*
X1179035Y656762D01*
X1178215Y656913D01*
X1177279Y658273D01*
X1177431Y659093D01*
X1176495Y660452D01*
X1175675Y660604D01*
X1174740Y661963D01*
X1174891Y662784D01*
X1173956Y664143D01*
X1173135Y664295D01*
X1172200Y665654D01*
X1172352Y666474D01*
X1171416Y667834D01*
X1170596Y667985D01*
X1169660Y669344D01*
X1169812Y670165D01*
X1142659Y709623D01*
X1141894Y709765D01*
X1140959Y711124D01*
X1141100Y711889D01*
X1140165Y713248D01*
X1139400Y713389D01*
X1138465Y714749D01*
X1138606Y715513D01*
X1137671Y716873D01*
X1136906Y717014D01*
X1135971Y718373D01*
X1136112Y719138D01*
X1135177Y720497D01*
X1134412Y720639D01*
X1133476Y721998D01*
X1133618Y722763D01*
X1130325Y727548D01*
X1118097Y737383D01*
X1109387Y740162D01*
X1099455Y736988D01*
X1088594Y728250D01*
X1085063Y714868D01*
X1085062D01*
X1088002Y701040D01*
X1093099Y693188D01*
X1095671Y691519D01*
X1098992D01*
X1102929Y695456D01*
X1116479D01*
G02X1119042Y694304I1J-3424D01*
G01X1119363Y693662D01*
G03X1120101Y693416I492J246D01*
G01X1123031Y694881D01*
G01X1518701Y72245D02*
Y73864D01*
G02X1518847Y74217I500J0D01*
G01X1518909Y74279D01*
G02X1519262Y74425I353J-354D01*
G01X1519263Y74426D01*
X1520906D01*
G03X1522073Y74908I1J1650D01*
G01X1522337Y75173D01*
G03X1522819Y76339I-1168J1165D01*
G01Y131327D01*
X1491049Y177233D01*
X1459282Y251539D01*
X1131182Y728339D01*
X1131177D01*
X1118651Y738414D01*
X1109387Y741370D01*
X1098900Y738019D01*
X1087578Y728910D01*
X1083880Y714897D01*
X1086921Y700593D01*
X1092267Y692356D01*
X1095330Y690369D01*
X1099469D01*
X1103406Y694306D01*
X1116480D01*
G02X1118088Y693640I0J-2274D01*
G01X1118334Y693148D01*
G02X1118088Y692410I-492J-246D01*
G01X1115157Y690944D01*
G01X1398228Y73819D02*
Y72375D01*
G02X1398082Y72022I-500J0D01*
G01X1397848Y71788D01*
G02X1397495Y71642I-353J354D01*
G01X1393198D01*
X1350913Y88053D01*
Y88052D01*
X1308628Y104461D01*
X1285476Y136337D01*
X1147055Y206454D01*
X1146813Y207193D01*
X1145341Y207939D01*
X1144602Y207697D01*
X1143130Y208442D01*
X1142888Y209182D01*
X1141416Y209927D01*
X1140677Y209685D01*
X1139205Y210431D01*
X1138963Y211170D01*
X1137491Y211915D01*
X1136752Y211673D01*
X1124463Y217898D01*
X1121708D01*
G02X1120100Y218564I0J2274D01*
G01X1119854Y219056D01*
G02X1120100Y219794I492J246D01*
G01X1123031Y221260D01*
G01X1398228Y68307D02*
Y69767D01*
G03X1398082Y70120I-500J0D01*
G01X1397856Y70346D01*
G03X1397503Y70492I-353J-354D01*
G01X1392982D01*
X1307896Y103511D01*
X1284708Y135436D01*
X1146534Y205428D01*
X1146535D01*
X1124188Y216748D01*
X1121709D01*
G02X1119146Y217900I-1J3424D01*
G01X1118825Y218542D01*
G03X1118087Y218788I-492J-246D01*
G01X1115157Y217323D01*
G01X1405315Y77756D02*
Y76137D01*
G02X1405169Y75784I-500J0D01*
G01X1405107Y75722D01*
G02X1404754Y75576I-353J354D01*
G01X1403110D01*
G02X1402347Y76339I0J763D01*
G01Y121276D01*
X1401497Y122804D01*
X1386624Y133237D01*
X1326108Y147336D01*
X1160432Y212062D01*
X1151042Y218274D01*
X1150898Y218981D01*
X1149522Y219891D01*
X1148815Y219747D01*
X1147439Y220657D01*
X1147295Y221364D01*
X1145919Y222274D01*
X1145212Y222131D01*
X1143836Y223041D01*
X1143692Y223748D01*
X1142316Y224658D01*
X1141609Y224514D01*
X1129652Y232424D01*
X1123629Y233646D01*
X1121708D01*
G02X1120100Y234312I0J2274D01*
G01X1119854Y234804D01*
G02X1120100Y235542I492J246D01*
G01X1123031Y237008D01*
G01X1405315Y72245D02*
Y73864D01*
G03X1405169Y74217I-500J0D01*
G01X1405107Y74279D01*
G03X1404754Y74425I-353J-354D01*
G01X1404753Y74426D01*
X1403110D01*
G02X1401197Y76339I0J1913D01*
G01Y120977D01*
X1400620Y122014D01*
X1386146Y132167D01*
X1325766Y146234D01*
X1159900Y211035D01*
X1129204Y231341D01*
X1123513Y232496D01*
X1121708D01*
G02X1119146Y233648I0J3424D01*
G01X1118825Y234290D01*
G03X1118087Y234536I-492J-246D01*
G01X1115157Y233071D01*
G01X1412402Y73819D02*
Y72200D01*
G02X1412256Y71847I-500J0D01*
G01X1412194Y71785D01*
G02X1411841Y71639I-353J354D01*
G01X1410197D01*
G02X1409844Y71785I0J500D01*
G01X1409580Y72049D01*
G02X1409434Y72402I354J353D01*
G01Y123279D01*
X1408113Y125653D01*
X1398574Y131731D01*
X1389116Y137757D01*
Y137758D01*
X1389117D01*
X1341545Y148840D01*
X1190517Y207889D01*
X1146763Y236850D01*
X1146620Y237557D01*
X1145244Y238467D01*
X1144537Y238324D01*
X1143161Y239234D01*
X1143017Y239941D01*
X1141641Y240852D01*
X1140935Y240708D01*
X1139559Y241619D01*
X1139415Y242326D01*
X1138039Y243236D01*
X1137332Y243092D01*
X1129409Y248337D01*
X1124213Y249394D01*
X1121708D01*
G02X1120100Y250060I0J2274D01*
G01X1119854Y250552D01*
G02X1120100Y251290I492J246D01*
G01X1123031Y252756D01*
G01X1412402Y68307D02*
Y69987D01*
G03X1412298Y70238I-355J0D01*
G01X1412194Y70342D01*
G03X1411841Y70488I-353J-354D01*
G01X1411840Y70489D01*
X1410197D01*
G02X1409030Y70971I-1J1650D01*
G01X1408766Y71236D01*
G02X1408284Y72402I1168J1165D01*
G01Y122980D01*
X1407249Y124839D01*
X1388663Y136681D01*
Y136682D01*
X1341203Y147738D01*
X1189984Y206862D01*
X1128960Y247254D01*
X1124097Y248244D01*
X1121709D01*
G02X1119146Y249396I-1J3424D01*
G01X1118825Y250038D01*
G03X1118087Y250284I-492J-246D01*
G01X1115157Y248819D01*
G01X1419488Y77756D02*
Y76137D01*
G02X1419342Y75784I-500J0D01*
G01X1419280Y75722D01*
G02X1418927Y75576I-353J354D01*
G01X1417283D01*
G02X1416930Y75722I0J500D01*
G01X1416666Y75986D01*
G02X1416520Y76339I354J353D01*
G01Y122004D01*
X1412862Y128586D01*
X1386793Y145197D01*
Y145198D01*
X1386628Y145303D01*
X1337800Y156679D01*
X1143848Y254921D01*
X1143623Y255607D01*
X1142151Y256352D01*
X1141466Y256128D01*
X1139994Y256873D01*
X1139769Y257559D01*
X1138298Y258304D01*
X1137612Y258080D01*
X1136140Y258825D01*
X1135916Y259511D01*
X1134444Y260256D01*
X1133758Y260032D01*
X1129091Y262396D01*
X1124944Y265142D01*
X1121708D01*
G02X1120100Y265808I0J2274D01*
G01X1119854Y266300D01*
G02X1120100Y267038I492J246D01*
G01X1123031Y268504D01*
G01X1419488Y72245D02*
Y73864D01*
G03X1419342Y74217I-500J0D01*
G01X1419280Y74279D01*
G03X1418927Y74425I-353J-354D01*
G01X1418926Y74426D01*
X1417283D01*
G02X1416116Y74908I-1J1650D01*
G01X1415852Y75173D01*
G02X1415370Y76339I1168J1165D01*
G01Y121705D01*
X1411998Y127772D01*
X1386175Y144227D01*
X1337404Y155590D01*
X1128512Y261400D01*
X1124597Y263992D01*
X1121709D01*
G02X1119146Y265144I-1J3424D01*
G01X1118825Y265786D01*
G03X1118087Y266032I-492J-246D01*
G01X1115157Y264567D01*
G01X1123031Y284252D02*
X1120100Y282786D01*
G03X1119854Y282048I246J-492D01*
G01X1120100Y281556D01*
G03X1121708Y280890I1608J1608D01*
G01X1125623D01*
X1128464Y280311D01*
X1134317Y276437D01*
X1135023Y276581D01*
X1136399Y275670D01*
X1136543Y274964D01*
X1137919Y274053D01*
X1138626Y274197D01*
X1140002Y273286D01*
X1140145Y272579D01*
X1141521Y271669D01*
X1142228Y271812D01*
X1143604Y270902D01*
X1143748Y270195D01*
X1199915Y233019D01*
X1378086Y156936D01*
X1378166Y156886D01*
Y156885D01*
X1421292Y129403D01*
X1423607Y125238D01*
Y72402D01*
G03X1423753Y72049I500J0D01*
G01X1424017Y71785D01*
G03X1424370Y71639I353J354D01*
G01X1426014D01*
G03X1426367Y71785I0J500D01*
G01X1426429Y71847D01*
G03X1426575Y72200I-354J353D01*
G01Y73819D01*
G01X1115157Y280315D02*
X1118087Y281780D01*
G02X1118825Y281534I246J-492D01*
G01X1119146Y280892D01*
G03X1121709Y279740I2562J2272D01*
G01X1125507D01*
X1128015Y279228D01*
X1199367Y232002D01*
X1377548Y155915D01*
X1420428Y128589D01*
X1422457Y124939D01*
Y72402D01*
G03X1422939Y71236I1650J-1D01*
G01X1423203Y70971D01*
G03X1424370Y70489I1166J1168D01*
G01X1426013D01*
X1426014Y70488D01*
G02X1426367Y70342I0J-500D01*
G01X1426471Y70238D01*
G02X1426575Y69987I-251J-251D01*
G01Y68307D01*
G01X1123031Y300000D02*
X1120100Y298534D01*
G03X1119854Y297796I246J-492D01*
G01X1120100Y297304D01*
G03X1121708Y296638I1608J1608D01*
G01X1124306D01*
X1128075Y295872D01*
X1138853Y288738D01*
X1139560Y288882D01*
X1140936Y287971D01*
X1141080Y287264D01*
X1142456Y286354D01*
X1143162Y286498D01*
X1144538Y285587D01*
X1144682Y284880D01*
X1146058Y283969D01*
X1146765Y284113D01*
X1148141Y283202D01*
X1148284Y282496D01*
X1175425Y264532D01*
X1211124Y240903D01*
X1356223Y178943D01*
X1423046Y136193D01*
X1430693Y122446D01*
Y76339D01*
G03X1430839Y75986I500J0D01*
G01X1431103Y75722D01*
G03X1431456Y75576I353J354D01*
G01X1433100D01*
G03X1433453Y75722I0J500D01*
G01X1433515Y75784D01*
G03X1433661Y76137I-354J353D01*
G01Y77756D01*
G01X1115157Y296063D02*
X1118087Y297528D01*
G02X1118825Y297282I246J-492D01*
G01X1119146Y296640D01*
G03X1121709Y295488I2562J2272D01*
G01X1124190D01*
X1127626Y294789D01*
X1174789Y263572D01*
Y263571D01*
X1210576Y239886D01*
X1355683Y177923D01*
X1422181Y135380D01*
X1429543Y122147D01*
Y76339D01*
G03X1430025Y75173I1650J-1D01*
G01X1430289Y74908D01*
G03X1431456Y74426I1166J1168D01*
G01X1433099D01*
X1433100Y74425D01*
G02X1433453Y74279I0J-500D01*
G01X1433515Y74217D01*
G02X1433661Y73864I-354J-353D01*
G01Y72245D01*
G01X1123031Y315748D02*
X1120100Y314282D01*
G03X1119854Y313544I246J-492D01*
G01X1120101Y313052D01*
G03X1121707Y312386I1608J1608D01*
G01X1126482D01*
X1176336Y302696D01*
X1176934Y303100D01*
X1178553Y302785D01*
X1178957Y302187D01*
X1180576Y301872D01*
X1181174Y302275D01*
X1182794Y301961D01*
X1183197Y301363D01*
X1184817Y301048D01*
X1185415Y301451D01*
X1187035Y301136D01*
X1187438Y300538D01*
X1246469Y289064D01*
X1373046Y208422D01*
X1387964Y185009D01*
X1413491Y167101D01*
X1437780Y123427D01*
Y72402D01*
G03X1437926Y72049I500J0D01*
G01X1438190Y71785D01*
G03X1438543Y71639I353J354D01*
G01X1440187D01*
G03X1440540Y71785I0J500D01*
G01X1440602Y71847D01*
G03X1440748Y72200I-354J353D01*
G01Y73819D01*
G01X1115157Y311811D02*
X1118087Y313276D01*
G02X1118825Y313030I246J-492D01*
G01X1119147Y312388D01*
G03X1121706Y311236I2561J2272D01*
G01X1126371D01*
X1246035Y287976D01*
X1372213Y207589D01*
X1379664Y195894D01*
Y195895D01*
X1387116Y184198D01*
X1412614Y166311D01*
X1436630Y123128D01*
Y72402D01*
G03X1437112Y71236I1650J-1D01*
G01X1437376Y70971D01*
G03X1438543Y70489I1166J1168D01*
G01X1440186D01*
X1440187Y70488D01*
G02X1440540Y70342I0J-500D01*
G01X1440644Y70238D01*
G02X1440748Y69987I-251J-251D01*
G01Y68307D01*
G01X1123031Y331496D02*
X1120100Y330030D01*
G03X1119854Y329292I246J-492D01*
G01X1120100Y328800D01*
G03X1121708Y328134I1608J1608D01*
G01X1127620D01*
X1177096Y318517D01*
X1177694Y318920D01*
X1179313Y318605D01*
X1179717Y318007D01*
X1181336Y317693D01*
X1181934Y318096D01*
X1183554Y317781D01*
X1183957Y317183D01*
X1185577Y316868D01*
X1186175Y317272D01*
X1187795Y316957D01*
X1188198Y316359D01*
X1235520Y307160D01*
X1402289Y200941D01*
X1444867Y136717D01*
Y76339D01*
G03X1445013Y75986I500J0D01*
G01X1445277Y75722D01*
G03X1445630Y75576I353J354D01*
G01X1447274D01*
G03X1447627Y75722I0J500D01*
G01X1447689Y75784D01*
G03X1447835Y76137I-354J353D01*
G01Y77756D01*
G01X1115157Y327559D02*
X1118087Y329024D01*
G02X1118825Y328778I246J-492D01*
G01X1119146Y328136D01*
G03X1121709Y326984I2562J2272D01*
G01X1127509D01*
X1235086Y306072D01*
X1401465Y200102D01*
X1443717Y136370D01*
Y76339D01*
G03X1444199Y75173I1650J-1D01*
G01X1444463Y74908D01*
G03X1445630Y74426I1166J1168D01*
G01X1447273D01*
X1447274Y74425D01*
G02X1447627Y74279I0J-500D01*
G01X1447689Y74217D01*
G02X1447835Y73864I-354J-353D01*
G01Y72245D01*
G01X1511614Y73819D02*
Y72200D01*
G03X1511760Y71847I500J0D01*
G01X1511822Y71785D01*
G03X1512175Y71639I353J354D01*
G01X1513819D01*
G03X1514172Y71785I0J500D01*
G01X1514436Y72049D01*
G03X1514582Y72402I-354J353D01*
G01Y131084D01*
X1484391Y174692D01*
X1453009Y248089D01*
X1230949Y571088D01*
X1230184Y571229D01*
X1229249Y572589D01*
X1229391Y573354D01*
X1228456Y574713D01*
X1227691Y574855D01*
X1226757Y576215D01*
X1226898Y576980D01*
X1203280Y611334D01*
X1202515Y611476D01*
X1201580Y612836D01*
X1201722Y613601D01*
X1200787Y614960D01*
X1200022Y615102D01*
X1199088Y616462D01*
X1199229Y617226D01*
X1198295Y618586D01*
X1197530Y618728D01*
X1196595Y620087D01*
X1196737Y620852D01*
X1174115Y653757D01*
X1173295Y653909D01*
X1172360Y655268D01*
X1172512Y656089D01*
X1171577Y657449D01*
X1170757Y657601D01*
X1169822Y658960D01*
X1169974Y659781D01*
X1169039Y661140D01*
X1168218Y661292D01*
X1167284Y662652D01*
X1167436Y663472D01*
X1166501Y664832D01*
X1165680Y664984D01*
X1164746Y666344D01*
X1164898Y667164D01*
X1144567Y696737D01*
X1143802Y696878D01*
X1142867Y698238D01*
X1143009Y699003D01*
X1142074Y700362D01*
X1141309Y700504D01*
X1140375Y701864D01*
X1140516Y702629D01*
X1139582Y703988D01*
X1138817Y704130D01*
X1137882Y705490D01*
X1138024Y706254D01*
X1137089Y707614D01*
X1136324Y707756D01*
X1135389Y709115D01*
X1135531Y709880D01*
X1125007Y725188D01*
X1115948Y732471D01*
X1109372Y734575D01*
X1102222Y732287D01*
X1094331Y725944D01*
X1092564Y719250D01*
X1093664Y716635D01*
X1096056Y715142D01*
X1098496D01*
X1098497Y715143D01*
X1099449D01*
X1103388Y711204D01*
X1116479D01*
G02X1119042Y710052I1J-3424D01*
G01X1119363Y709410D01*
G03X1120101Y709164I492J246D01*
G01X1123031Y710629D01*
G01X1511614Y68307D02*
Y69927D01*
G02X1511760Y70280I500J0D01*
G01X1511822Y70342D01*
G02X1512175Y70488I353J-354D01*
G01X1512176Y70489D01*
X1513819D01*
G03X1514986Y70971I1J1650D01*
G01X1515250Y71236D01*
G03X1515732Y72402I-1168J1165D01*
G01Y131444D01*
X1485403Y175251D01*
X1454022Y248647D01*
X1125859Y725979D01*
X1116502Y733502D01*
X1109372Y735783D01*
X1101668Y733318D01*
X1093315Y726604D01*
X1091352Y719165D01*
X1092745Y715852D01*
X1095726Y713992D01*
X1098973D01*
X1102911Y710054D01*
X1116480D01*
G02X1118088Y709388I0J-2274D01*
G01X1118334Y708896D01*
G02X1118088Y708158I-492J-246D01*
G01X1115157Y706692D01*
G54D11*
X292153Y486059D03*
X306388Y486022D03*
X320474Y379474D03*
X316534D03*
X320474Y363234D03*
X316534D03*
X320925Y485385D03*
X315925D03*
X320474Y832229D03*
X316534D03*
X320925Y938140D03*
X315600Y933600D03*
X407714Y761291D03*
X398254Y763517D03*
X441645Y288847D03*
Y284647D03*
X444687Y379474D03*
X440747D03*
X444687Y363234D03*
X440747D03*
X445138Y487743D03*
X440138D03*
X416303Y486022D03*
X430538Y485985D03*
X444687Y832229D03*
X440747D03*
X444687Y816765D03*
X440747D03*
X445138Y938140D03*
X440138D03*
X539350Y487659D03*
X534350D03*
X510621Y486059D03*
X524856Y486022D03*
X568899Y379474D03*
X564959D03*
X568899Y363234D03*
X564959D03*
X593079Y516531D03*
Y512531D03*
X568899Y832229D03*
X564959D03*
X569350Y941640D03*
X564350D03*
X652663Y502400D03*
X647663D03*
X624028Y503558D03*
X638263Y503494D03*
X689232Y355251D03*
X693112Y385976D03*
X689172D03*
Y358978D03*
X658681Y571798D03*
X654681D03*
X724283Y860689D03*
X737984Y861689D03*
X741883Y861389D03*
X747383Y924689D03*
X757664Y868974D03*
X753893Y912630D03*
X792336Y1319537D03*
X782230Y1323670D03*
X785340Y1320410D03*
X789549Y1322310D03*
X777009Y1322690D03*
X781290Y1328490D03*
X825984Y-458D03*
X833671Y254D03*
X802362Y-458D03*
X810236D03*
X818110D03*
X802350Y35923D03*
X802036Y1164244D03*
X870600Y476900D03*
X851800Y477200D03*
X888800Y1493500D03*
X893020Y1566530D03*
X892700Y1543900D03*
X892558Y1528458D03*
X942000Y752850D03*
X927601Y1384433D03*
X923486Y1384268D03*
X897400Y1574000D03*
X969463Y1177599D03*
X955500Y1369000D03*
X979963Y1545689D03*
X1032080Y-45980D03*
X1040180Y437510D03*
X1028657Y1009103D03*
X1020654Y1023940D03*
X1018094Y1021240D03*
X1015534Y1023840D03*
X1012974Y1021240D03*
X1013700Y1007640D03*
X1009509Y1009850D03*
X1023214Y1007140D03*
X994923Y1137488D03*
X995948Y1184250D03*
X1017354Y1196124D03*
X1021061Y1198543D03*
X1028000Y1404700D03*
X1043000Y-67600D03*
X1043112Y-34912D03*
X1066600Y-72800D03*
X1066225Y-40278D03*
X1054593Y-51122D03*
X1074425Y447225D03*
X1071950Y453288D03*
X1043674Y451921D03*
X1069018Y456900D03*
X1065985Y460500D03*
X1083633Y932172D03*
X1073408Y942399D03*
X1058571Y943852D03*
X1053099Y1021657D03*
X1048512Y1021378D03*
X1052522Y1145153D03*
X1047000Y1258687D03*
X1051300Y1253300D03*
X1100929Y-90371D03*
X1116600Y-85538D03*
X1124024Y-30840D03*
X1128765Y-34297D03*
X1094200Y-38400D03*
X1146768Y-31238D03*
X1139808Y-31171D03*
X1149699Y-35153D03*
X1142293Y-37522D03*
X1152800Y1223062D03*
X1152700Y1216213D03*
X1407936Y552099D03*
Y548099D03*
G54D21*
G01X1511450Y181700D02*
X1510498D01*
G02X1510145Y181846I0J500D01*
G01X1510084Y181907D01*
G02X1509938Y182260I354J353D01*
G01Y184452D01*
X1492688Y224539D01*
X1484117Y244458D01*
X1475495Y264497D01*
X1224639Y629267D01*
X1185850Y804276D01*
X1220934Y962557D01*
X1186292Y1120000D01*
X1153894Y1168949D01*
X1141379Y1176921D01*
X1136800Y1177935D01*
X1133740Y1178613D01*
G03X1133648Y1178623I-92J-415D01*
G01X1099473D01*
G03X1098201Y1178097I0J-1801D01*
G01X1098052Y1177948D01*
G03X1097526Y1176676I1275J-1272D01*
G01Y1174970D01*
G02X1097380Y1174617I-500J0D01*
G01X1097339Y1174576D01*
G02X1096986Y1174430I-353J354D01*
G01X1095420D01*
G01X1506950Y181700D02*
X1508130D01*
G03X1508483Y181846I0J500D01*
G01X1508492Y181855D01*
G03X1508638Y182208I-354J353D01*
G01Y184184D01*
X1491493Y224025D01*
X1474351Y263866D01*
X1223424Y628738D01*
X1184518Y804275D01*
X1219602Y962558D01*
X1185074Y1119484D01*
X1165927Y1148412D01*
X1159916Y1157494D01*
X1158773Y1157727D01*
X1158069Y1158790D01*
X1158302Y1159933D01*
X1157598Y1160996D01*
X1156455Y1161229D01*
X1155751Y1162292D01*
X1155984Y1163435D01*
X1155280Y1164499D01*
X1154137Y1164731D01*
X1153433Y1165794D01*
X1153666Y1166938D01*
X1152962Y1168001D01*
X1140874Y1175701D01*
Y1175700D01*
X1133552Y1177323D01*
X1099473D01*
G03X1099120Y1177177I0J-500D01*
G01X1098972Y1177029D01*
G03X1098826Y1176676I354J-353D01*
G01Y1174970D01*
G03X1098972Y1174617I500J0D01*
G01X1099013Y1174576D01*
G03X1099366Y1174430I353J354D01*
G01X1100932D01*
G01X1632438Y175242D02*
Y174113D01*
G02X1632300Y173780I-471J0D01*
G02X1631967Y173642I-333J333D01*
G01X1628951D01*
X1588232Y186932D01*
X1470047Y282026D01*
X1232642Y627253D01*
X1191794Y811514D01*
X1225671Y964295D01*
X1206342Y1051448D01*
X1197940Y1089334D01*
X1189486Y1127456D01*
X1157492Y1175794D01*
X1156964Y1176131D01*
X1151324Y1179723D01*
X1145259Y1183586D01*
G03X1145123Y1183642I-227J-359D01*
G01X1135851Y1185699D01*
G03X1135759Y1185709I-92J-415D01*
G01X1103527D01*
G03X1102255Y1185183I0J-1801D01*
G01X1101989Y1184917D01*
G03X1101463Y1183645I1275J-1272D01*
G01Y1182039D01*
G02X1101317Y1181686I-500J0D01*
G01X1101293Y1181662D01*
G02X1100940Y1181516I-353J354D01*
G01X1099357D01*
G01X1632438Y170742D02*
Y171871D01*
G03X1632300Y172204I-471J0D01*
G03X1631967Y172342I-333J-333D01*
G01X1628744D01*
X1587602Y185770D01*
X1528324Y233466D01*
X1528323Y233467D01*
X1469083Y281132D01*
X1231425Y626727D01*
X1190462Y811514D01*
X1224339Y964295D01*
X1205072Y1051166D01*
X1188269Y1126939D01*
X1163821Y1163876D01*
X1162677Y1164109D01*
X1161974Y1165172D01*
X1162206Y1166316D01*
X1161502Y1167379D01*
X1160359Y1167611D01*
X1159655Y1168675D01*
X1159888Y1169818D01*
X1159184Y1170881D01*
X1158041Y1171114D01*
X1157337Y1172177D01*
X1157570Y1173320D01*
X1156560Y1174846D01*
X1144691Y1182406D01*
X1135663Y1184409D01*
X1103527D01*
G03X1103174Y1184263I0J-500D01*
G01X1102909Y1183998D01*
G03X1102763Y1183645I354J-353D01*
G01Y1182039D01*
G03X1102909Y1181686I500J0D01*
G01X1102933Y1181662D01*
G03X1103286Y1181516I353J354D01*
G01X1104869D01*
G01X1756650Y175242D02*
Y174113D01*
G02X1756512Y173780I-471J0D01*
G02X1756179Y173642I-333J333D01*
G01X1752334D01*
X1729093Y181229D01*
Y181228D01*
X1705852Y188814D01*
X1540321Y322001D01*
X1377097Y427997D01*
X1305314Y532258D01*
X1240175Y626870D01*
X1238974Y632288D01*
X1198622Y814290D01*
X1231800Y963959D01*
X1194225Y1133417D01*
X1164051Y1179005D01*
X1145356Y1190921D01*
X1136900Y1192796D01*
X1099473D01*
G03X1098201Y1192270I0J-1801D01*
G01X1098052Y1192121D01*
G03X1097526Y1190849I1275J-1272D01*
G01Y1189143D01*
G02X1097380Y1188790I-500J0D01*
G01X1097339Y1188749D01*
G02X1096986Y1188603I-353J354D01*
G01X1095420D01*
G01X1756650Y170742D02*
Y171871D01*
G03X1756512Y172204I-471J0D01*
G03X1756179Y172342I-333J-333D01*
G01X1752127D01*
X1705222Y187652D01*
X1539557Y320946D01*
X1376172Y427047D01*
X1238960Y626341D01*
X1197290Y814290D01*
X1230468Y963959D01*
X1193008Y1132900D01*
X1170073Y1167550D01*
X1168930Y1167783D01*
X1168226Y1168846D01*
X1168459Y1169989D01*
X1167755Y1171052D01*
X1166612Y1171285D01*
X1165908Y1172348D01*
X1166141Y1173491D01*
X1165437Y1174555D01*
X1164294Y1174787D01*
X1163590Y1175850D01*
X1163823Y1176994D01*
X1163119Y1178057D01*
X1161556Y1179053D01*
X1153984Y1183879D01*
X1144851Y1189701D01*
X1136757Y1191496D01*
X1099473D01*
G03X1099120Y1191350I0J-500D01*
G01X1098972Y1191202D01*
G03X1098826Y1190849I354J-353D01*
G01Y1189143D01*
G03X1098972Y1188790I500J0D01*
G01X1099013Y1188749D01*
G03X1099366Y1188603I353J354D01*
G01X1100932D01*
G01X1099357Y1195690D02*
X1100940D01*
G03X1101293Y1195836I0J500D01*
G01X1101317Y1195860D01*
G03X1101463Y1196213I-354J353D01*
G01Y1197819D01*
G02X1101989Y1199091I1801J0D01*
G01X1102255Y1199357D01*
G02X1103527Y1199883I1272J-1275D01*
G01X1137298D01*
X1146321Y1197881D01*
X1169878Y1182871D01*
X1200135Y1137158D01*
X1229938Y1002720D01*
X1239918Y957704D01*
X1206713Y807891D01*
X1245967Y630814D01*
X1380138Y435716D01*
X1565396Y315401D01*
X1746254Y256371D01*
X1823739Y194028D01*
X1877588Y173642D01*
X1880392D01*
G03X1880725Y173780I0J471D01*
G03X1880863Y174113I-333J333D01*
G01Y175242D01*
G01X1104869Y1195690D02*
X1103286D01*
G02X1102933Y1195836I0J500D01*
G01X1102909Y1195860D01*
G02X1102763Y1196213I354J353D01*
G01Y1197819D01*
G02X1102909Y1198172I500J0D01*
G01X1103174Y1198437D01*
G02X1103527Y1198583I353J-354D01*
G01X1137155D01*
X1145815Y1196661D01*
X1168946Y1181923D01*
X1169650Y1180860D01*
X1169417Y1179716D01*
X1170121Y1178653D01*
X1171264Y1178421D01*
X1171968Y1177357D01*
X1171735Y1176214D01*
X1172439Y1175151D01*
X1173582Y1174918D01*
X1174286Y1173855D01*
X1174053Y1172712D01*
X1174757Y1171649D01*
X1175900Y1171416D01*
X1198918Y1136641D01*
X1218751Y1047173D01*
X1238586Y957704D01*
X1205381Y807891D01*
X1244752Y630285D01*
X1379213Y434766D01*
X1472058Y374468D01*
X1564830Y314217D01*
X1745624Y255209D01*
X1764895Y239704D01*
X1764896Y239703D01*
X1823085Y192885D01*
X1877350Y172342D01*
X1880392D01*
G02X1880725Y172204I0J-471D01*
G02X1880863Y171871I-333J-333D01*
G01Y170742D01*
G01X1095420Y1245296D02*
X1096986D01*
G03X1097339Y1245442I0J500D01*
G01X1097380Y1245483D01*
G03X1097526Y1245836I-354J353D01*
G01Y1247542D01*
G02X1098052Y1248814I1801J0D01*
G01X1098201Y1248963D01*
G02X1099473Y1249489I1272J-1275D01*
G01X1131895D01*
X1135838Y1248615D01*
X1150254Y1239433D01*
X1202761Y1156904D01*
X1246718Y958965D01*
X1213577Y809491D01*
X1253089Y631277D01*
X1255317Y627754D01*
X1256673Y626398D01*
X1259137D01*
G03X1259800Y627061I0J663D01*
G01Y627998D01*
G01Y623498D02*
Y624435D01*
G03X1259137Y625098I-663J0D01*
G01X1256134D01*
X1254295Y626936D01*
X1251868Y630774D01*
X1217246Y786932D01*
X1217247D01*
X1212245Y809491D01*
X1228878Y884509D01*
X1245386Y958965D01*
X1201541Y1156399D01*
X1160686Y1220613D01*
X1159547Y1220866D01*
X1158863Y1221942D01*
X1159116Y1223080D01*
X1158431Y1224156D01*
X1157292Y1224409D01*
X1156608Y1225485D01*
X1156861Y1226624D01*
X1156177Y1227700D01*
X1155038Y1227953D01*
X1154353Y1229029D01*
X1154607Y1230168D01*
X1149311Y1238491D01*
X1135333Y1247395D01*
X1131752Y1248189D01*
X1099473D01*
G03X1099120Y1248043I0J-500D01*
G01X1098972Y1247895D01*
G03X1098826Y1247542I354J-353D01*
G01Y1245836D01*
G03X1098972Y1245483I500J0D01*
G01X1099013Y1245442D01*
G03X1099366Y1245296I353J354D01*
G01X1100932D01*
G01X1099357Y1252382D02*
X1100940D01*
G03X1101293Y1252528I0J500D01*
G01X1101317Y1252552D01*
G03X1101463Y1252905I-354J353D01*
G01Y1254511D01*
G02X1101989Y1255783I1801J0D01*
G01X1102255Y1256049D01*
G02X1103527Y1256575I1272J-1275D01*
G01X1134809D01*
X1138999Y1255647D01*
X1153302Y1246537D01*
X1206946Y1162345D01*
X1239475Y1015637D01*
X1303560Y915043D01*
X1316722Y894381D01*
X1330003Y873531D01*
X1354499Y767166D01*
X1362710Y731505D01*
X1353342Y687416D01*
X1346604Y655706D01*
X1349978Y639821D01*
X1353251Y634794D01*
X1362987Y628469D01*
X1377058Y625474D01*
X1381406Y626398D01*
X1383542D01*
G03X1383875Y626536I0J471D01*
G03X1384013Y626869I-333J333D01*
G01Y627998D01*
G01X1104869Y1252382D02*
X1103286D01*
G02X1102933Y1252528I0J500D01*
G01X1102909Y1252552D01*
G02X1102763Y1252905I354J353D01*
G01Y1254511D01*
G02X1102909Y1254864I500J0D01*
G01X1103174Y1255129D01*
G02X1103527Y1255275I353J-354D01*
G01X1134666D01*
X1138494Y1254427D01*
X1152360Y1245595D01*
X1153045Y1244520D01*
X1152793Y1243381D01*
X1153478Y1242305D01*
X1154617Y1242053D01*
X1155302Y1240978D01*
X1155050Y1239839D01*
X1155735Y1238763D01*
X1156874Y1238511D01*
X1157559Y1237436D01*
X1157306Y1236296D01*
X1157992Y1235221D01*
X1159131Y1234969D01*
X1205726Y1161840D01*
X1221940Y1088710D01*
X1230068Y1052054D01*
X1238255Y1015132D01*
X1302463Y914344D01*
X1315625Y893682D01*
X1328786Y873021D01*
X1345083Y802256D01*
X1357338Y749042D01*
X1361378Y731494D01*
X1356724Y709590D01*
Y709589D01*
X1354397Y698637D01*
X1353785Y695761D01*
X1353367Y693789D01*
X1352070Y687686D01*
X1345274Y655706D01*
X1348756Y639314D01*
X1352311Y633853D01*
X1362480Y627247D01*
X1369753Y625699D01*
X1377058Y624144D01*
X1381543Y625098D01*
X1383542D01*
G02X1383875Y624960I0J-471D01*
G02X1384013Y624627I-333J-333D01*
G01Y623498D01*
G01X1508225Y627998D02*
Y626869D01*
G02X1508087Y626536I-471J0D01*
G02X1507754Y626398I-333J333D01*
G01X1505925D01*
X1505094Y626920D01*
X1471307Y680991D01*
Y680990D01*
X1353054Y870234D01*
X1301318Y953029D01*
X1293928Y964855D01*
X1236062Y1057463D01*
X1211676Y1167488D01*
X1159961Y1248649D01*
X1138287Y1262459D01*
X1134266Y1263351D01*
X1133633Y1263491D01*
X1132861Y1263662D01*
X1099473D01*
G03X1098201Y1263136I0J-1801D01*
G01X1098052Y1262987D01*
G03X1097526Y1261715I1275J-1272D01*
G01Y1260009D01*
G02X1097380Y1259656I-500J0D01*
G01X1097339Y1259615D01*
G02X1096986Y1259469I-353J354D01*
G01X1095420D01*
G01X1508225Y623498D02*
Y624627D01*
G03X1508087Y624960I-471J0D01*
G03X1507754Y625098I-333J-333D01*
G01X1505550D01*
X1504149Y625977D01*
X1470204Y680301D01*
X1351950Y869545D01*
X1351951D01*
X1322388Y916856D01*
X1319923Y920800D01*
X1307606Y940512D01*
X1307605D01*
X1303910Y946427D01*
X1292825Y964166D01*
X1234840Y1056963D01*
X1210456Y1166983D01*
X1166046Y1236679D01*
X1164907Y1236931D01*
X1164222Y1238007D01*
X1164474Y1239146D01*
X1163789Y1240221D01*
X1162650Y1240473D01*
X1161965Y1241549D01*
X1162217Y1242688D01*
X1161532Y1243763D01*
X1160393Y1244015D01*
X1159708Y1245091D01*
X1159960Y1246230D01*
X1159019Y1247707D01*
X1137782Y1261239D01*
X1133984Y1262081D01*
X1132718Y1262362D01*
X1099473D01*
G03X1099120Y1262216I0J-500D01*
G01X1098972Y1262068D01*
G03X1098826Y1261715I354J-353D01*
G01Y1260009D01*
G03X1098972Y1259656I500J0D01*
G01X1099013Y1259615D01*
G03X1099366Y1259469I353J354D01*
G01X1100932D01*
G01X1099357Y1266556D02*
X1100940D01*
G03X1101293Y1266702I0J500D01*
G01X1101317Y1266726D01*
G03X1101463Y1267079I-354J353D01*
G01Y1268685D01*
G02X1101989Y1269957I1801J0D01*
G01X1102255Y1270223D01*
G02X1103527Y1270749I1272J-1275D01*
G01X1134942D01*
X1139031Y1269843D01*
X1164702Y1253488D01*
X1217001Y1171399D01*
X1236807Y1082071D01*
X1237221Y1080204D01*
X1238155Y1075996D01*
X1239501Y1069921D01*
X1465257Y715833D01*
X1596642Y632130D01*
X1622491Y626398D01*
X1631967D01*
G03X1632300Y626536I0J471D01*
G03X1632438Y626869I-333J333D01*
G01Y627998D01*
G01X1104869Y1266556D02*
X1103286D01*
G02X1102933Y1266702I0J500D01*
G01X1102909Y1266726D01*
G02X1102763Y1267079I354J353D01*
G01Y1268685D01*
G02X1102909Y1269038I500J0D01*
G01X1103174Y1269303D01*
G02X1103527Y1269449I353J-354D01*
G01X1134799D01*
X1138526Y1268623D01*
X1163760Y1252546D01*
X1164445Y1251471D01*
X1164193Y1250332D01*
X1164878Y1249256D01*
X1166017Y1249004D01*
X1166702Y1247928D01*
X1166449Y1246789D01*
X1167134Y1245714D01*
X1168273Y1245462D01*
X1168959Y1244386D01*
X1168706Y1243247D01*
X1169391Y1242172D01*
X1170530Y1241919D01*
X1215781Y1170894D01*
X1235537Y1081788D01*
X1238281Y1069416D01*
X1464315Y714891D01*
X1596137Y630910D01*
X1622348Y625098D01*
X1631967D01*
G02X1632300Y624960I0J-471D01*
G02X1632438Y624627I-333J-333D01*
G01Y623498D01*
G01X1731650Y627998D02*
Y626869D01*
G02X1731512Y626536I-471J0D01*
G02X1731179Y626398I-333J333D01*
G01X1726052D01*
X1699891Y637708D01*
X1400376Y828517D01*
X1244151Y1073744D01*
X1221396Y1176434D01*
X1170257Y1256717D01*
X1138012Y1277263D01*
X1135434Y1277835D01*
X1099473D01*
G03X1098201Y1277309I0J-1801D01*
G01X1098052Y1277160D01*
G03X1097526Y1275888I1275J-1272D01*
G01Y1274182D01*
G02X1097380Y1273829I-500J0D01*
G01X1097339Y1273788D01*
G02X1096986Y1273642I-353J354D01*
G01X1095420D01*
G01X1731650Y623498D02*
Y624627D01*
G03X1731512Y624960I-471J0D01*
G03X1731179Y625098I-333J-333D01*
G01X1725783D01*
X1699279Y636555D01*
X1587257Y707921D01*
X1587256D01*
X1549978Y731669D01*
X1399434Y827575D01*
X1321167Y950432D01*
X1242931Y1073239D01*
X1220176Y1175929D01*
X1176084Y1245148D01*
X1174945Y1245400D01*
X1174260Y1246476D01*
X1174513Y1247615D01*
X1173828Y1248690D01*
X1172689Y1248943D01*
X1172004Y1250018D01*
X1172256Y1251157D01*
X1171571Y1252233D01*
X1170432Y1252485D01*
X1169747Y1253561D01*
X1170000Y1254700D01*
X1169315Y1255775D01*
X1137507Y1276043D01*
X1136399Y1276288D01*
X1135291Y1276534D01*
Y1276535D01*
X1099473D01*
G03X1099120Y1276389I0J-500D01*
G01X1098972Y1276241D01*
G03X1098826Y1275888I354J-353D01*
G01Y1274182D01*
G03X1098972Y1273829I500J0D01*
G01X1099013Y1273788D01*
G03X1099366Y1273642I353J354D01*
G01X1100932D01*
G01X1880863Y627998D02*
Y626869D01*
G02X1880725Y626536I-471J0D01*
G02X1880392Y626398I-333J333D01*
G01X1873552D01*
X1841033Y634031D01*
X1821033Y650182D01*
X1804817Y679585D01*
X1783288Y764828D01*
X1724533Y865670D01*
X1718169Y869780D01*
X1708768Y875851D01*
X1692798Y886163D01*
X1468156Y931857D01*
X1364083Y998160D01*
X1260013Y1064462D01*
X1256177Y1070482D01*
Y1070483D01*
X1252340Y1076504D01*
Y1076503D01*
X1252339Y1076508D01*
X1230127Y1176696D01*
X1176528Y1260832D01*
X1140520Y1283770D01*
X1135338Y1284922D01*
X1103527D01*
G03X1102255Y1284396I0J-1801D01*
G01X1101989Y1284130D01*
G03X1101463Y1282858I1275J-1272D01*
G01Y1281252D01*
G02X1101317Y1280899I-500J0D01*
G01X1101293Y1280875D01*
G02X1100940Y1280729I-353J354D01*
G01X1099357D01*
G01X1880863Y623498D02*
Y624627D01*
G03X1880725Y624960I-471J0D01*
G03X1880392Y625098I-333J-333D01*
G01X1873401D01*
X1840447Y632833D01*
X1820017Y649330D01*
X1811786Y664256D01*
X1803597Y679104D01*
X1782072Y764332D01*
X1723566Y864746D01*
X1708062Y874758D01*
X1692298Y884937D01*
X1467660Y930630D01*
X1259071Y1063520D01*
X1256998Y1066774D01*
X1254877Y1070103D01*
X1253640Y1072045D01*
X1253639Y1072044D01*
X1251120Y1075998D01*
X1228907Y1176191D01*
X1182356Y1249263D01*
X1181217Y1249516D01*
X1180532Y1250591D01*
X1180784Y1251730D01*
X1180099Y1252805D01*
X1178960Y1253058D01*
X1178275Y1254133D01*
X1178528Y1255272D01*
X1177843Y1256348D01*
X1176704Y1256600D01*
X1176018Y1257676D01*
X1176271Y1258815D01*
X1175586Y1259890D01*
X1140014Y1282550D01*
X1135195Y1283622D01*
X1103527D01*
G03X1103174Y1283476I0J-500D01*
G01X1102909Y1283211D01*
G03X1102763Y1282858I354J-353D01*
G01Y1281252D01*
G03X1102909Y1280899I500J0D01*
G01X1102933Y1280875D01*
G03X1103286Y1280729I353J354D01*
G01X1104869D01*
G01X1756650Y1080754D02*
Y1079625D01*
G02X1756512Y1079292I-471J0D01*
G02X1756179Y1079154I-333J333D01*
G01X1750405D01*
X1690343Y1105836D01*
X1419989Y1300760D01*
X1139824Y1362875D01*
X1099473D01*
G03X1098201Y1362349I0J-1801D01*
G01X1098052Y1362200D01*
G03X1097526Y1360928I1275J-1272D01*
G01Y1359222D01*
G02X1097380Y1358869I-500J0D01*
G01X1097339Y1358828D01*
G02X1096986Y1358682I-353J354D01*
G01X1095420D01*
G01X1756650Y1076254D02*
Y1077383D01*
G03X1756512Y1077716I-471J0D01*
G03X1756179Y1077854I-333J-333D01*
G01X1750129D01*
X1689692Y1104702D01*
X1419446Y1299548D01*
X1411914Y1301218D01*
X1410930Y1300591D01*
X1409685Y1300867D01*
X1409058Y1301851D01*
X1407814Y1302127D01*
X1406830Y1301500D01*
X1405585Y1301776D01*
X1404958Y1302760D01*
X1403713Y1303036D01*
X1402729Y1302409D01*
X1401484Y1302685D01*
X1400858Y1303669D01*
X1139681Y1361575D01*
X1099473D01*
G03X1099120Y1361429I0J-500D01*
G01X1098972Y1361281D01*
G03X1098826Y1360928I354J-353D01*
G01Y1359222D01*
G03X1098972Y1358869I500J0D01*
G01X1099013Y1358828D01*
G03X1099366Y1358682I353J354D01*
G01X1100932D01*
G01X1880863Y1080754D02*
Y1079625D01*
G02X1880725Y1079292I-471J0D01*
G02X1880392Y1079154I-333J333D01*
G01X1873678D01*
X1805096Y1094358D01*
X1416466Y1307598D01*
X1398501Y1311581D01*
X1365599Y1318876D01*
X1135191Y1369951D01*
G03X1135099Y1369961I-92J-415D01*
G01X1103527D01*
G03X1102255Y1369435I0J-1801D01*
G01X1101989Y1369169D01*
G03X1101463Y1367897I1275J-1272D01*
G01Y1366291D01*
G02X1101317Y1365938I-500J0D01*
G01X1101293Y1365914D01*
G02X1100940Y1365768I-353J354D01*
G01X1099357D01*
G01X1880863Y1076254D02*
Y1077383D01*
G03X1880725Y1077716I-471J0D01*
G03X1880392Y1077854I-333J-333D01*
G01X1873535D01*
X1804633Y1093129D01*
X1416003Y1306369D01*
X1409277Y1307860D01*
X1408293Y1307233D01*
X1407048Y1307509D01*
X1406421Y1308493D01*
X1405176Y1308769D01*
X1404192Y1308142D01*
X1402947Y1308418D01*
X1402320Y1309402D01*
X1401076Y1309678D01*
X1400092Y1309051D01*
X1398847Y1309327D01*
X1398220Y1310311D01*
X1135003Y1368661D01*
X1103527D01*
G03X1103174Y1368515I0J-500D01*
G01X1102909Y1368250D01*
G03X1102763Y1367897I354J-353D01*
G01Y1366291D01*
G03X1102909Y1365938I500J0D01*
G01X1102933Y1365914D01*
G03X1103286Y1365768I353J354D01*
G01X1104869D01*
G01X1095420Y1330335D02*
X1096986D01*
G03X1097339Y1330481I0J500D01*
G01X1097380Y1330522D01*
G03X1097526Y1330875I-354J353D01*
G01Y1332581D01*
G02X1098052Y1333853I1801J0D01*
G01X1098201Y1334002D01*
G02X1099473Y1334528I1272J-1275D01*
G01X1132156D01*
X1135568Y1333772D01*
X1151771Y1323450D01*
X1230283Y1200211D01*
X1257014Y1079632D01*
X1257609Y1079154D01*
X1259312D01*
G03X1259657Y1079297I0J488D01*
G03X1259800Y1079642I-345J345D01*
G01Y1080754D01*
G01Y1076254D02*
Y1077470D01*
G03X1259688Y1077742I-384J1D01*
G01X1259687Y1077743D01*
G03X1259417Y1077854I-270J-273D01*
G01X1257301D01*
G02X1257036Y1077947I0J424D01*
G01X1256496Y1078379D01*
X1256345Y1078501D01*
X1255843Y1078904D01*
X1229063Y1199706D01*
X1160405Y1307477D01*
X1159266Y1307730D01*
X1158581Y1308805D01*
X1158833Y1309944D01*
X1158148Y1311019D01*
X1157009Y1311272D01*
X1156324Y1312347D01*
X1156576Y1313486D01*
X1155891Y1314562D01*
X1154752Y1314814D01*
X1154067Y1315890D01*
X1154320Y1317029D01*
X1150829Y1322508D01*
X1135063Y1332552D01*
X1132013Y1333228D01*
X1099473D01*
G03X1099120Y1333082I0J-500D01*
G01X1098972Y1332934D01*
G03X1098826Y1332581I354J-353D01*
G01Y1330875D01*
G03X1098972Y1330522I500J0D01*
G01X1099013Y1330481D01*
G03X1099366Y1330335I353J354D01*
G01X1100932D01*
G01X1099357Y1337422D02*
X1100940D01*
G03X1101293Y1337568I0J500D01*
G01X1101317Y1337592D01*
G03X1101463Y1337945I-354J353D01*
G01Y1339551D01*
G02X1101989Y1340823I1801J0D01*
G01X1102255Y1341089D01*
G02X1103527Y1341615I1272J-1275D01*
G01X1135465D01*
X1140763Y1340441D01*
X1171590Y1320801D01*
X1298296Y1121908D01*
X1327242Y1100586D01*
X1365320Y1084512D01*
X1378013Y1079154D01*
X1383542D01*
G03X1383875Y1079292I0J471D01*
G03X1384013Y1079625I-333J333D01*
G01Y1080754D01*
G01X1104869Y1337422D02*
X1103286D01*
G02X1102933Y1337568I0J500D01*
G01X1102909Y1337592D01*
G02X1102763Y1337945I354J353D01*
G01Y1339551D01*
G02X1102909Y1339904I500J0D01*
G01X1103174Y1340169D01*
G02X1103527Y1340315I353J-354D01*
G01X1135322D01*
X1140258Y1339221D01*
X1170648Y1319859D01*
X1172955Y1316238D01*
X1172702Y1315099D01*
X1173387Y1314024D01*
X1174526Y1313771D01*
X1175211Y1312696D01*
X1174959Y1311557D01*
X1175644Y1310482D01*
X1176783Y1310229D01*
X1177468Y1309154D01*
X1177215Y1308015D01*
X1177900Y1306939D01*
X1179039Y1306687D01*
X1179040D01*
X1297329Y1121004D01*
X1326594Y1099447D01*
X1377749Y1077854D01*
X1383542D01*
G02X1383875Y1077716I0J-471D01*
G02X1384013Y1077383I-333J-333D01*
G01Y1076254D01*
G01X1095420Y1344508D02*
X1096986D01*
G03X1097339Y1344654I0J500D01*
G01X1097380Y1344695D01*
G03X1097526Y1345048I-354J353D01*
G01Y1346754D01*
G02X1098052Y1348026I1801J0D01*
G01X1098201Y1348175D01*
G02X1099473Y1348701I1272J-1275D01*
G01X1133998D01*
X1142361Y1346849D01*
X1177365Y1324549D01*
X1207049Y1277957D01*
X1276886Y1232530D01*
X1294151Y1207438D01*
X1491035Y1082010D01*
X1503899Y1079155D01*
Y1079156D01*
X1503900Y1079155D01*
Y1079154D01*
X1507754D01*
G03X1508087Y1079292I0J471D01*
G03X1508225Y1079625I-333J333D01*
G01Y1080754D01*
G01X1100932Y1344508D02*
X1099366D01*
G02X1099013Y1344654I0J500D01*
G01X1098972Y1344695D01*
G02X1098826Y1345048I354J353D01*
G01Y1346754D01*
G02X1098972Y1347107I500J0D01*
G01X1099120Y1347255D01*
G02X1099473Y1347401I353J-354D01*
G01X1133855D01*
X1137855Y1346515D01*
X1141856Y1345629D01*
X1176423Y1323607D01*
X1178396Y1320510D01*
X1178144Y1319370D01*
X1178829Y1318295D01*
X1179968Y1318043D01*
X1180653Y1316967D01*
X1180401Y1315828D01*
X1181086Y1314753D01*
X1182225Y1314500D01*
X1182910Y1313425D01*
X1182657Y1312286D01*
X1183342Y1311211D01*
X1184481Y1310958D01*
X1191262Y1300315D01*
X1206103Y1277020D01*
X1275960Y1231580D01*
X1293229Y1206483D01*
X1490529Y1080790D01*
X1503757Y1077854D01*
X1507754D01*
G02X1508087Y1077716I0J-471D01*
G02X1508225Y1077383I-333J-333D01*
G01Y1076254D01*
G01X1632438Y1080754D02*
Y1079625D01*
G02X1632300Y1079292I-471J0D01*
G02X1631967Y1079154I-333J333D01*
G01X1629712D01*
X1615091Y1084739D01*
X1460533Y1188993D01*
X1319862Y1220181D01*
X1208149Y1291350D01*
X1185618Y1326718D01*
X1168956Y1337332D01*
X1141341Y1354924D01*
X1137581Y1355757D01*
X1137550Y1355788D01*
X1103527D01*
G03X1102255Y1355262I0J-1801D01*
G01X1101989Y1354996D01*
G03X1101463Y1353724I1275J-1272D01*
G01Y1352118D01*
G02X1101317Y1351765I-500J0D01*
G01X1101293Y1351741D01*
G02X1100940Y1351595I-353J354D01*
G01X1099357D01*
G01X1632438Y1076254D02*
Y1077383D01*
G03X1632300Y1077716I-471J0D01*
G03X1631967Y1077854I-333J-333D01*
G01X1629472D01*
X1614487Y1083577D01*
X1460011Y1187777D01*
X1319357Y1218961D01*
X1207207Y1290408D01*
X1199087Y1303155D01*
X1191446Y1315149D01*
X1190307Y1315402D01*
X1189622Y1316477D01*
X1189874Y1317616D01*
X1189189Y1318691D01*
X1188050Y1318944D01*
X1187365Y1320019D01*
X1187618Y1321158D01*
X1186933Y1322234D01*
X1185794Y1322486D01*
X1185108Y1323562D01*
X1185361Y1324701D01*
X1184676Y1325776D01*
X1168257Y1336235D01*
X1140836Y1353704D01*
X1137300Y1354487D01*
Y1354488D01*
X1103527D01*
G03X1103174Y1354342I0J-500D01*
G01X1102909Y1354077D01*
G03X1102763Y1353724I354J-353D01*
G01Y1352118D01*
G03X1102909Y1351765I500J0D01*
G01X1102933Y1351741D01*
G03X1103286Y1351595I353J354D01*
G01X1104869D01*
G54D12*
X429724Y68307D03*
X458071D03*
X443898D03*
X429724Y73819D03*
X458071D03*
X450984Y77756D03*
Y72245D03*
X443898Y73819D03*
X436811Y77756D03*
Y72245D03*
X472244Y68307D03*
X479331Y77756D03*
Y72245D03*
X472244Y73819D03*
X465157Y77756D03*
Y72245D03*
X514764Y68307D03*
X543110D03*
X528937D03*
X557283D03*
X514764Y73819D03*
X550197Y77756D03*
Y72245D03*
X543110Y73819D03*
X536024Y77756D03*
Y72245D03*
X528937Y73819D03*
X521850Y77756D03*
Y72245D03*
X557283Y73819D03*
X564370Y77756D03*
Y72245D03*
X826772Y1616536D03*
X833859Y1640945D03*
Y1646457D03*
X826772Y1622048D03*
X840945Y1630709D03*
X826772D03*
X840945Y1636221D03*
X826772D03*
X876378Y1640945D03*
X862205D03*
X848032D03*
X876378Y1646457D03*
X862205D03*
X848032D03*
X890552Y1630709D03*
X869292D03*
X855118D03*
X869292Y1636221D03*
X855118D03*
X897638Y1612599D03*
X904725Y1636221D03*
X897638Y1622441D03*
Y1626772D03*
Y1632284D03*
Y1646457D03*
X1095420Y1174430D03*
X1100932D03*
X1095420Y1188603D03*
X1100932D03*
X1109593Y1216949D03*
X1099357Y1181516D03*
Y1195690D03*
X1104869Y1181516D03*
Y1195690D03*
X1113530Y1224036D03*
X1095420Y1245296D03*
Y1259469D03*
Y1273642D03*
X1100932Y1245296D03*
Y1259469D03*
Y1273642D03*
X1109593Y1231123D03*
X1099357Y1252382D03*
Y1266556D03*
X1104869Y1252382D03*
Y1266556D03*
X1113530Y1238209D03*
X1109593Y1316162D03*
X1115105D03*
X1099357Y1280729D03*
X1104869D03*
X1095420Y1330335D03*
Y1344508D03*
Y1358682D03*
X1100932Y1330335D03*
Y1344508D03*
Y1358682D03*
X1099357Y1337422D03*
Y1351595D03*
Y1365768D03*
X1104869Y1337422D03*
Y1351595D03*
Y1365768D03*
X1115105Y1401201D03*
X1398228Y68307D03*
X1426575D03*
X1412402D03*
X1398228Y73819D03*
X1426575D03*
X1419488Y77756D03*
Y72245D03*
X1412402Y73819D03*
X1405315Y77756D03*
Y72245D03*
X1440748Y68307D03*
X1447835Y77756D03*
Y72245D03*
X1440748Y73819D03*
X1433661Y77756D03*
Y72245D03*
X1483268Y68307D03*
X1511614D03*
X1497441D03*
X1483268Y73819D03*
X1518701Y77756D03*
Y72245D03*
X1511614Y73819D03*
X1504528Y77756D03*
Y72245D03*
X1497441Y73819D03*
X1490354Y77756D03*
Y72245D03*
X1525787Y68307D03*
X1532874Y77756D03*
Y72245D03*
X1525787Y73819D03*
G54D22*
G01X292153Y486059D02*
X302500Y475712D01*
Y372200D01*
X314200Y360500D01*
X317740D01*
X320474Y363234D01*
G01X306388Y486022D02*
X310085Y482325D01*
Y369683D01*
X316534Y363234D01*
G01X320925Y485385D02*
Y379925D01*
X320474Y379474D01*
G01X315925Y485385D02*
Y380083D01*
X316534Y379474D01*
G01X320925Y938140D02*
X320474Y937689D01*
Y832229D01*
G01X316534D02*
X317800Y833495D01*
Y931400D01*
X315600Y933600D01*
G01X444687Y816765D02*
Y807245D01*
X407714Y770272D01*
Y761291D01*
G01X440747Y816765D02*
Y806010D01*
X398254Y763517D01*
G01X870600Y476900D02*
X867700Y479800D01*
X844000D01*
X695811Y331611D01*
X553824D01*
X511060Y288847D01*
X441645D01*
G01X851800Y477200D02*
X845800D01*
X697336Y328736D01*
X555015D01*
X510926Y284647D01*
X441645D01*
G01X445138Y487743D02*
Y379925D01*
X444687Y379474D01*
G01X440138Y487743D02*
Y380083D01*
X440747Y379474D01*
G01X416303Y486022D02*
X426713Y475612D01*
Y372200D01*
X438513Y360400D01*
X441853D01*
X444687Y363234D01*
G01X430538Y485985D02*
X434298Y482225D01*
Y369683D01*
X440747Y363234D01*
G01X445138Y938140D02*
X447600Y935678D01*
Y835142D01*
X444687Y832229D01*
G01X440138Y938140D02*
X440747Y937531D01*
Y832229D01*
G01X510621Y486059D02*
Y448779D01*
X550474Y408926D01*
Y372651D01*
X562725Y360400D01*
X566065D01*
X568899Y363234D01*
G01X539350Y487659D02*
Y441217D01*
X568899Y411668D01*
Y379474D01*
G01X534350Y487659D02*
Y441217D01*
X563899Y411668D01*
Y380534D01*
X564959Y379474D01*
G01X524856Y486022D02*
Y440906D01*
X558059Y407703D01*
Y370134D01*
X564959Y363234D01*
G01X569350Y941640D02*
X568899Y941189D01*
Y832229D01*
G01X564350Y941640D02*
X564959Y941031D01*
Y832229D01*
G01X624028Y503558D02*
Y477283D01*
X677849Y423462D01*
Y365051D01*
X687649Y355251D01*
X689232D01*
G01X652663Y502400D02*
Y477786D01*
X693112Y437337D01*
Y385976D01*
G01X647663Y502400D02*
Y477786D01*
X688112Y437337D01*
Y387036D01*
X689172Y385976D01*
G01X638263Y503494D02*
Y475284D01*
X681272Y432275D01*
Y366878D01*
X689172Y358978D01*
G01X781290Y1328490D02*
X781260D01*
X779632Y1326862D01*
Y1223813D01*
X762910Y1207091D01*
Y1177318D01*
X779632Y1160596D01*
Y1091726D01*
X801625Y1069733D01*
Y957775D01*
X911200Y848200D01*
Y790071D01*
X947050Y754221D01*
Y740037D01*
X964435Y722652D01*
Y612106D01*
X1003300Y573241D01*
Y512472D01*
X1068547Y447225D01*
X1074425D01*
G01X1071950Y453288D02*
X1071938Y453300D01*
X1066043D01*
X1005825Y513518D01*
Y574287D01*
X966960Y613152D01*
Y723698D01*
X959214Y731444D01*
Y750070D01*
X949484Y759800D01*
X948300D01*
X914149Y793951D01*
Y851011D01*
X804150Y961010D01*
Y1070779D01*
X782242Y1092687D01*
Y1163377D01*
X766803Y1178816D01*
Y1206201D01*
X782242Y1221640D01*
Y1323658D01*
X782230Y1323670D01*
G01X1069018Y456900D02*
X1066014D01*
X1008350Y514564D01*
Y575333D01*
X969486Y614197D01*
Y724743D01*
X961739Y732490D01*
Y751116D01*
X951904Y760951D01*
Y762379D01*
X916740Y797543D01*
Y851991D01*
X806675Y962056D01*
Y1071825D01*
X787024Y1091476D01*
Y1318726D01*
X785340Y1320410D01*
G01X777009Y1322690D02*
Y1233314D01*
X760128Y1216433D01*
Y1174946D01*
X769617Y1165457D01*
Y1098170D01*
X799100Y1068687D01*
Y956729D01*
X908675Y847154D01*
Y789025D01*
X908787Y788913D01*
Y783788D01*
X937138Y755437D01*
X942263D01*
X944525Y753175D01*
Y738991D01*
X961910Y721606D01*
Y611060D01*
X1000775Y572195D01*
Y494820D01*
X1043674Y451921D01*
G01X1065985Y460500D02*
X1010875Y515610D01*
Y576380D01*
X972011Y615244D01*
Y725789D01*
X964264Y733536D01*
Y752162D01*
X954429Y761997D01*
Y763425D01*
X919265Y798589D01*
Y854391D01*
X809200Y964456D01*
Y1073400D01*
X789549Y1093051D01*
Y1322310D01*
G01X802036Y1164244D02*
Y1176306D01*
X792497Y1185845D01*
Y1319537D01*
X792336D01*
G01X1124024Y-30840D02*
X1122411D01*
X1096403Y-4832D01*
X934266D01*
X920739Y8695D01*
X835137D01*
X825984Y-458D01*
G01X1128765Y-34297D02*
X1123085D01*
X1095485Y-6697D01*
X933659D01*
X920133Y6829D01*
X840246D01*
X833671Y254D01*
G01X802350Y35923D02*
X822175Y16098D01*
X924171D01*
X938168Y2101D01*
X1111554D01*
X1144793Y-31138D01*
X1146668D01*
X1146768Y-31238D01*
G01X1139808Y-31171D02*
X1108316Y321D01*
X936882D01*
X923028Y14175D01*
X816995D01*
X802362Y-458D01*
G01X1149699Y-35153D02*
X1138474D01*
X1104679Y-1358D01*
X935969D01*
X922302Y12309D01*
X823003D01*
X810236Y-458D01*
G01X1142293Y-37522D02*
X1136050D01*
X1101565Y-3037D01*
X935269D01*
X921788Y10444D01*
X829012D01*
X818110Y-458D01*
G01X890552Y1630709D02*
X886730Y1626887D01*
Y1580830D01*
X873950Y1568050D01*
Y1489974D01*
X878384Y1485540D01*
Y1457209D01*
X900487Y1435106D01*
Y1317313D01*
X941138Y1276662D01*
Y1164073D01*
X993273Y1111938D01*
Y1051904D01*
X993736Y1051441D01*
Y1050393D01*
X994716Y1049413D01*
X994717D01*
X1000536Y1043594D01*
Y1013678D01*
X1008537Y1005677D01*
X1015608D01*
X1019020Y1009089D01*
X1022387D01*
X1022401Y1009103D01*
X1028657D01*
G01X893020Y1566530D02*
X885662Y1559172D01*
Y1509189D01*
X887505Y1507346D01*
Y1497155D01*
X886760Y1496410D01*
Y1463178D01*
X908862Y1441076D01*
Y1325870D01*
X951088Y1283644D01*
Y1165968D01*
X1001648Y1115408D01*
Y1055374D01*
X1015000Y1042022D01*
Y1031057D01*
X1018094Y1027963D01*
Y1021240D01*
G01X897638Y1632284D02*
X902168Y1627754D01*
Y1586345D01*
X899584Y1583761D01*
X899230D01*
X883576Y1568107D01*
Y1507614D01*
X885225Y1505965D01*
Y1497244D01*
X885084Y1497103D01*
Y1462485D01*
X907187Y1440382D01*
Y1325175D01*
X949413Y1282949D01*
Y1165274D01*
X999973Y1114714D01*
Y1054680D01*
X1010018Y1044635D01*
Y1031616D01*
X1015534Y1026100D01*
Y1023840D01*
G01X897638Y1626772D02*
X900243Y1624167D01*
Y1587143D01*
X881901Y1568801D01*
Y1506607D01*
X883550Y1504958D01*
Y1497938D01*
X883409Y1497797D01*
Y1459291D01*
X905512Y1437188D01*
Y1324481D01*
X947738Y1282255D01*
Y1164580D01*
X998298Y1114020D01*
Y1053986D01*
X998761Y1053523D01*
Y1053400D01*
X1005730Y1046431D01*
Y1031544D01*
X1012974Y1024300D01*
Y1021240D01*
G01X897638Y1622441D02*
X893042Y1617845D01*
Y1594194D01*
X890973Y1592125D01*
Y1582611D01*
X881231Y1572869D01*
X881230D01*
X879231Y1570870D01*
X879230D01*
Y1570868D01*
X878551Y1570189D01*
Y1505219D01*
X880200Y1503570D01*
Y1499326D01*
X880059Y1499185D01*
Y1457903D01*
X902162Y1435800D01*
Y1320138D01*
X942813Y1279487D01*
Y1164767D01*
X994948Y1112632D01*
Y1052598D01*
X995411Y1052135D01*
Y1051088D01*
X1002211Y1044288D01*
Y1014372D01*
X1008943Y1007640D01*
X1013700D01*
G01X897638Y1612599D02*
X894967Y1609928D01*
Y1584236D01*
X880906Y1570175D01*
X880905D01*
Y1570174D01*
X880226Y1569495D01*
Y1505913D01*
X881875Y1504264D01*
Y1498632D01*
X881734Y1498491D01*
Y1458597D01*
X903837Y1436494D01*
Y1321963D01*
X944488Y1281312D01*
Y1165461D01*
X996623Y1113326D01*
Y1053292D01*
X997086Y1052829D01*
Y1052600D01*
X1003886Y1045800D01*
Y1018723D01*
X1009509Y1013100D01*
Y1009850D01*
G01X897638Y1646457D02*
X894359Y1649736D01*
Y1651989D01*
X893253Y1653095D01*
X889564D01*
X884100Y1647631D01*
Y1580569D01*
X872275Y1568744D01*
Y1489280D01*
X876709Y1484846D01*
Y1456515D01*
X898812Y1434412D01*
Y1312988D01*
X939400Y1272400D01*
Y1163442D01*
X991598Y1111244D01*
Y1051210D01*
X991800Y1051008D01*
Y1049961D01*
X992061Y1049700D01*
Y1049699D01*
X994022Y1047738D01*
X994023D01*
X998861Y1042900D01*
Y1012984D01*
X1007843Y1004002D01*
X1016302D01*
X1019440Y1007140D01*
X1023214D01*
G01X888800Y1493500D02*
X888960Y1493660D01*
X892800D01*
X897349Y1489111D01*
Y1454958D01*
X910537Y1441770D01*
Y1326564D01*
X952763Y1284338D01*
Y1166662D01*
X1003323Y1116102D01*
Y1056068D01*
X1020654Y1038737D01*
Y1023940D01*
G01X942000Y752850D02*
Y737945D01*
X959385Y720560D01*
Y610014D01*
X998250Y571149D01*
Y493774D01*
X1037961Y454063D01*
Y439729D01*
X1040180Y437510D01*
G01X923486Y1384268D02*
Y1377173D01*
X928219Y1372440D01*
X961163D01*
X1015018Y1318585D01*
X1082247D01*
X1082424Y1318762D01*
X1106993D01*
X1109593Y1316162D01*
G01X927601Y1384433D02*
Y1383412D01*
X926206Y1382017D01*
Y1378319D01*
X929128Y1375397D01*
X961777D01*
X1016064Y1321110D01*
X1082247D01*
X1082670Y1320687D01*
X1110580D01*
X1115105Y1316162D01*
G01X904725Y1636221D02*
X907800Y1633146D01*
Y1584400D01*
X897400Y1574000D01*
G01X1115105Y1316162D02*
X1110637Y1311694D01*
X1086538D01*
X1085938Y1311094D01*
X1063600D01*
X1023823Y1271317D01*
Y1198023D01*
X1021924Y1196124D01*
X1017354D01*
G01X1109593Y1316162D02*
X1107050Y1313619D01*
X1062554D01*
X1021061Y1272126D01*
Y1198543D01*
G01X1073408Y942399D02*
X1065316Y950491D01*
Y987673D01*
X1053099Y999890D01*
Y1021657D01*
G01X1048512Y1021378D02*
Y998487D01*
X1060500Y986499D01*
Y945781D01*
X1058571Y943852D01*
G01X1113530Y1238209D02*
X1110389Y1241350D01*
X1090850D01*
X1073513Y1258687D01*
X1047000D01*
G01X1109593Y1231123D02*
X1105316Y1235400D01*
X1092800D01*
X1074900Y1253300D01*
X1051300D01*
G01X1113530Y1224036D02*
X1116444Y1226950D01*
X1142639D01*
X1146527Y1223062D01*
X1152800D01*
G01X1109593Y1216949D02*
Y1217593D01*
X1112600Y1220600D01*
X1143310D01*
X1147697Y1216213D01*
X1152700D01*
G54D13*
X954921Y158268D03*
X947047Y154331D03*
X954921Y205512D03*
Y189764D03*
Y174016D03*
X947047Y201575D03*
Y185827D03*
Y170079D03*
X954921Y252756D03*
Y237008D03*
Y221260D03*
X947047Y248819D03*
Y233071D03*
Y217323D03*
X954921Y300000D03*
Y284252D03*
Y268504D03*
X947047Y296063D03*
Y280315D03*
Y264567D03*
X954921Y331496D03*
Y315748D03*
X947047Y327559D03*
Y311811D03*
X954921Y694881D03*
Y679133D03*
Y663385D03*
X947047Y690944D03*
Y675196D03*
Y659448D03*
X954921Y710629D03*
X947047Y706692D03*
X994305Y1566342D03*
X1123031Y158268D03*
X1115157Y154331D03*
X1123031Y205512D03*
Y189764D03*
Y174016D03*
X1115157Y201575D03*
Y185827D03*
Y170079D03*
X1123031Y252756D03*
Y237008D03*
Y221260D03*
X1115157Y248819D03*
Y233071D03*
Y217323D03*
X1123031Y300000D03*
Y284252D03*
Y268504D03*
X1115157Y296063D03*
Y280315D03*
Y264567D03*
X1123031Y331496D03*
Y315748D03*
X1115157Y327559D03*
Y311811D03*
X1097441Y450787D03*
X1115157Y454724D03*
X1105315Y446850D03*
X1123031Y490157D03*
Y474409D03*
Y458661D03*
X1115157Y501968D03*
Y486220D03*
Y470472D03*
X1123031Y505905D03*
Y600393D03*
X1115157Y596456D03*
X1123031Y647637D03*
Y631889D03*
Y616141D03*
X1115157Y643700D03*
Y627952D03*
Y612204D03*
X1123031Y694881D03*
Y679133D03*
Y663385D03*
X1115157Y690944D03*
Y675196D03*
Y659448D03*
X1123031Y710629D03*
X1115157Y706692D03*
G54D14*
X1039845Y1467746D03*
X1026345D03*
X1030845D03*
X1035345D03*
X1039845Y1463246D03*
X1026345D03*
X1030845D03*
X1035345D03*
X1005400Y1463157D03*
X1000900D03*
X996400D03*
X1009900D03*
X1005400Y1467657D03*
X1000900D03*
X996400D03*
X1009900D03*
X1035345Y1476746D03*
X1030845D03*
X1026345D03*
X1039845D03*
Y1472246D03*
X1026345D03*
X1030845D03*
X1035345D03*
X1005400Y1472157D03*
X1000900D03*
X996400D03*
X1009900D03*
Y1476657D03*
X1005400D03*
X1000900D03*
X996400D03*
X1023583Y1489593D03*
X995783D03*
X1000500Y1511400D03*
X1036578Y1511210D03*
X1014690Y1511178D03*
X1010190D03*
X1005690D03*
X1031790Y1511078D03*
X1027290D03*
X1019600Y1511100D03*
X1023583Y1501593D03*
Y1507593D03*
Y1495593D03*
X995783D03*
Y1501593D03*
Y1507593D03*
X1040583Y1517883D03*
X1031799Y1534392D03*
X1031882Y1528985D03*
X1026459Y1528919D03*
X1026376Y1534326D03*
X1014867D03*
X1014950Y1528919D03*
X1020290Y1534392D03*
X1020373Y1528985D03*
X1040500Y1529290D03*
X1040583Y1523883D03*
X1062700Y1463100D03*
X1058200D03*
X1067200D03*
X1062700Y1467600D03*
X1058200D03*
X1067200D03*
X1053700Y1463100D03*
Y1467600D03*
X1062700Y1472100D03*
X1058200D03*
X1067200D03*
Y1476600D03*
X1058200D03*
X1062700D03*
X1053700Y1472100D03*
Y1476600D03*
X1078683Y1489593D03*
X1051383D03*
X1041810Y1511084D03*
X1055310D03*
X1059810D03*
X1064310D03*
X1068810D03*
X1073310D03*
X1078683Y1495593D03*
Y1501593D03*
Y1507593D03*
Y1516593D03*
X1051383Y1495593D03*
Y1501593D03*
Y1507593D03*
X1078683Y1522593D03*
G54D15*
X1101457Y1601181D03*
X1119685D03*
X1108150D03*
X1126378D03*
G54D16*
G01X363248Y-425196D02*
Y-505196D01*
G01D02*
X1639148D01*
G01X359248Y-409196D02*
G02I-12000J0D01*
G01X354098D02*
G02I-6850J0D01*
G01X347248Y-425196D02*
Y-393196D01*
G01X363248Y-425196D02*
X1639148D01*
G01X363248Y-460696D02*
X1639148D01*
G01X363248Y-409196D02*
X331248D01*
G01X720748Y-425196D02*
Y-505196D01*
G01X858248Y-425196D02*
Y-505196D01*
G01X892558Y1528458D02*
X893887D01*
X914888Y1507457D01*
Y1335923D01*
X987587Y1263224D01*
Y1210038D01*
X1000619Y1197006D01*
Y1174983D01*
X1060000Y1115602D01*
Y1065728D01*
X1083633Y1042095D01*
Y932172D01*
G01X892700Y1543900D02*
X892558Y1543758D01*
Y1528458D01*
G01X979963Y1545689D02*
X973306Y1552346D01*
X907172D01*
X898726Y1543900D01*
X892700D01*
G01X973248Y-425196D02*
Y-505196D01*
G01X995948Y1184250D02*
X993900Y1186298D01*
X977679D01*
X974800Y1183419D01*
Y1182936D01*
X969463Y1177599D01*
G01X955500Y1369000D02*
X1000904Y1323596D01*
Y1200964D01*
X1003619Y1198249D01*
Y1180778D01*
X1039244Y1145153D01*
X1052522D01*
G01X994305Y1566342D02*
Y1552905D01*
X987089Y1545689D01*
X979963D01*
G01X995948Y1184250D02*
Y1138513D01*
X994923Y1137488D01*
G01X1115105Y1401201D02*
X1111606Y1404700D01*
X1028000D01*
G01X1100929Y-90371D02*
X1097671D01*
X1094900Y-87600D01*
Y-70220D01*
X1097620Y-67500D01*
Y-41820D01*
X1094200Y-38400D01*
G01X1116600Y-85538D02*
X1114845Y-87293D01*
X1104007D01*
X1100929Y-90371D01*
G01X1271648Y-425196D02*
Y-505196D01*
G01X1441648Y-425196D02*
Y-505196D01*
G01X1639148Y-425196D02*
Y-505196D01*
G01X1667148Y-409196D02*
G02I-12000J0D01*
G01X1661998D02*
G02I-6850J0D01*
G01X1655148Y-425196D02*
Y-393196D01*
G01X1671148Y-409196D02*
X1639148D01*
X1259800Y627998D03*
Y623498D03*
Y1080754D03*
Y1076254D03*
X1384013Y627998D03*
Y623498D03*
Y1080754D03*
Y1076254D03*
X1511450Y181700D03*
X1506950D03*
X1508225Y627998D03*
Y623498D03*
Y1080754D03*
Y1076254D03*
X1632438Y175242D03*
Y170742D03*
Y627998D03*
Y623498D03*
Y1080754D03*
Y1076254D03*
X1756650Y175242D03*
Y170742D03*
X1731650Y627998D03*
Y623498D03*
X1756650Y1080754D03*
Y1076254D03*
X1880863Y175242D03*
Y170742D03*
Y627998D03*
Y623498D03*
Y1080754D03*
Y1076254D03*
G54D17*
G01X753893Y912630D02*
X741883Y900620D01*
Y861389D01*
G01X747383Y924689D02*
X760104Y911968D01*
Y871414D01*
X757664Y868974D01*
G54D18*
G01X394744Y-485863D02*
X395618Y-484988D01*
X396273Y-483530D01*
X396710Y-481487D01*
X396273Y-479738D01*
X395400Y-478571D01*
X393871Y-477696D01*
X387976D01*
Y-495196D01*
X395181D01*
X396710Y-494030D01*
X397583Y-492279D01*
X398020Y-490238D01*
X397583Y-488196D01*
X396273Y-486446D01*
X394744Y-485863D01*
X387976D01*
G01X407441Y-495196D02*
Y-483530D01*
G01Y-485863D02*
X408533Y-484696D01*
X409625Y-483821D01*
X411153Y-483530D01*
X412244Y-483821D01*
X413555Y-484696D01*
G01X423413Y-500446D02*
X424723Y-501029D01*
X426470Y-500446D01*
X427561Y-499280D01*
X428435Y-497821D01*
X429744Y-493155D01*
X432583Y-483530D01*
G01X425596D02*
X429744Y-493155D01*
G01X448991Y-484988D02*
X447463Y-483821D01*
X446153Y-483530D01*
X444406Y-484113D01*
X443096Y-485279D01*
X442223Y-487321D01*
X442004Y-489363D01*
X442223Y-491405D01*
X443096Y-493155D01*
X444406Y-494613D01*
X446153Y-495196D01*
X447681Y-494613D01*
X448991Y-493446D01*
G01X459723Y-487321D02*
X466710D01*
X466055Y-485279D01*
X464963Y-484113D01*
X463435Y-483530D01*
X461906Y-483821D01*
X460596Y-484696D01*
X459723Y-486738D01*
X459286Y-488488D01*
Y-490238D01*
X459723Y-491988D01*
X460815Y-493738D01*
X462125Y-494904D01*
X463653Y-495196D01*
X465181Y-494613D01*
X466710Y-492863D01*
G01X502801Y-479155D02*
X501491Y-478279D01*
X499963Y-477696D01*
X498216D01*
X496251Y-478571D01*
X494723Y-480029D01*
X493631Y-481780D01*
X492758Y-484696D01*
X492539Y-487321D01*
X492976Y-489946D01*
X493631Y-491696D01*
X494941Y-493446D01*
X496470Y-494613D01*
X497998Y-495196D01*
X499526D01*
X501055Y-494613D01*
X502365Y-493738D01*
X503457Y-492572D01*
G01X519428Y-495196D02*
Y-483530D01*
G01Y-485571D02*
X518555Y-484405D01*
X517244Y-483821D01*
X515716Y-483530D01*
X514188Y-484113D01*
X512878Y-485279D01*
X512004Y-487029D01*
X511568Y-489363D01*
X512004Y-491696D01*
X512878Y-493446D01*
X514188Y-494613D01*
X515716Y-495196D01*
X517244Y-494904D01*
X518555Y-494030D01*
X519428Y-492863D01*
G01X529286Y-495196D02*
Y-483530D01*
G01Y-486446D02*
X530160Y-484988D01*
X531470Y-483821D01*
X533216Y-483530D01*
X534744Y-483821D01*
X536055Y-484988D01*
X536710Y-487029D01*
Y-495196D01*
G01X545913Y-500446D02*
X547223Y-501029D01*
X548970Y-500446D01*
X550061Y-499280D01*
X550935Y-497821D01*
X552244Y-493155D01*
X555083Y-483530D01*
G01X548096D02*
X552244Y-493155D01*
G01X567998Y-495196D02*
X566688Y-494904D01*
X565378Y-493738D01*
X564504Y-491696D01*
X564068Y-489363D01*
X564504Y-487029D01*
X565378Y-484988D01*
X566688Y-483821D01*
X567998Y-483530D01*
X569308Y-483821D01*
X570618Y-484988D01*
X571491Y-487029D01*
X571710Y-489363D01*
X571491Y-491696D01*
X570618Y-493738D01*
X569308Y-494904D01*
X567998Y-495196D01*
G01X581786D02*
Y-483530D01*
G01Y-486446D02*
X582660Y-484988D01*
X583970Y-483821D01*
X585716Y-483530D01*
X587244Y-483821D01*
X588555Y-484988D01*
X589210Y-487029D01*
Y-495196D01*
G01X616350D02*
Y-477696D01*
X624646D01*
G01X621590Y-486154D02*
X616350D01*
G01X637998Y-495779D02*
X637561Y-495488D01*
Y-494904D01*
X637998Y-494613D01*
X638435Y-494904D01*
Y-495488D01*
X637998Y-495779D01*
G01X650695Y-495196D02*
Y-477696D01*
X655061D01*
X656808Y-478571D01*
X658118Y-479738D01*
X659210Y-481487D01*
X660083Y-483530D01*
X660301Y-486446D01*
X660083Y-489363D01*
X659210Y-491405D01*
X658118Y-493155D01*
X656808Y-494321D01*
X655061Y-495196D01*
X650695D01*
G01X668631D02*
Y-477696D01*
X673871D01*
X675618Y-478571D01*
X676928Y-480613D01*
X677365Y-482946D01*
X676928Y-485279D01*
X675836Y-487029D01*
X673871Y-487905D01*
X668631D01*
G01X692244Y-485863D02*
X693118Y-484988D01*
X693773Y-483530D01*
X694210Y-481487D01*
X693773Y-479738D01*
X692900Y-478571D01*
X691371Y-477696D01*
X685476D01*
Y-495196D01*
X692681D01*
X694210Y-494030D01*
X695083Y-492279D01*
X695520Y-490238D01*
X695083Y-488196D01*
X693773Y-486446D01*
X692244Y-485863D01*
X685476D01*
G01X501071Y-450196D02*
Y-432696D01*
X506748Y-447279D01*
X512425Y-432696D01*
Y-450196D01*
G01X524248D02*
X522938Y-449904D01*
X521628Y-448738D01*
X520754Y-446696D01*
X520318Y-444363D01*
X520754Y-442029D01*
X521628Y-439988D01*
X522938Y-438821D01*
X524248Y-438530D01*
X525558Y-438821D01*
X526868Y-439988D01*
X527741Y-442029D01*
X527960Y-444363D01*
X527741Y-446696D01*
X526868Y-448738D01*
X525558Y-449904D01*
X524248Y-450196D01*
G01X545678Y-432696D02*
Y-450196D01*
G01Y-447572D02*
X544805Y-449030D01*
X543494Y-449904D01*
X541966Y-450196D01*
X540220Y-449613D01*
X538910Y-448155D01*
X538036Y-446405D01*
X537818Y-444363D01*
X538036Y-442321D01*
X538910Y-440571D01*
X540220Y-439113D01*
X541966Y-438530D01*
X543494Y-438821D01*
X544586Y-439405D01*
X545678Y-440571D01*
G01X555973Y-442321D02*
X562960D01*
X562305Y-440279D01*
X561213Y-439113D01*
X559685Y-438530D01*
X558156Y-438821D01*
X556846Y-439696D01*
X555973Y-441738D01*
X555536Y-443488D01*
Y-445238D01*
X555973Y-446988D01*
X557065Y-448738D01*
X558375Y-449904D01*
X559903Y-450196D01*
X561431Y-449613D01*
X562960Y-447863D01*
G01X576748Y-450196D02*
Y-432696D01*
G01X754448Y-495196D02*
Y-477696D01*
X751828Y-481196D01*
G01Y-495196D02*
X757068D01*
G01X767800Y-487905D02*
X769328Y-485863D01*
X770638Y-484696D01*
X772385Y-484113D01*
X773913Y-484696D01*
X775005Y-485863D01*
X775878Y-487613D01*
X776096Y-489654D01*
X775878Y-491405D01*
X775005Y-493155D01*
X773694Y-494613D01*
X772166Y-495196D01*
X770420Y-494613D01*
X768891Y-492863D01*
X768018Y-490238D01*
X767800Y-487321D01*
X768236Y-483530D01*
X768891Y-481487D01*
X769983Y-479446D01*
X771511Y-477988D01*
X773040Y-477696D01*
X774568Y-478279D01*
X775660Y-479738D01*
G01X784645Y-491696D02*
X785954Y-493738D01*
X787701Y-494904D01*
X789666Y-495196D01*
X791413Y-494904D01*
X793160Y-493446D01*
X794251Y-491696D01*
X794470Y-489946D01*
X794033Y-487905D01*
X792505Y-486446D01*
X790976Y-485863D01*
X789011D01*
G01X790976D02*
X792286Y-484988D01*
X793378Y-483530D01*
X793815Y-481780D01*
X793378Y-480029D01*
X792286Y-478571D01*
X790321Y-477696D01*
X788356Y-477988D01*
X786391Y-479155D01*
G01X806948Y-495196D02*
Y-477696D01*
X804328Y-481196D01*
G01Y-495196D02*
X809568D01*
G01X819645Y-492572D02*
X820954Y-494030D01*
X822483Y-494904D01*
X824448Y-495196D01*
X826413Y-494613D01*
X827941Y-493446D01*
X829033Y-491405D01*
X829251Y-489071D01*
X828815Y-486738D01*
X827723Y-485279D01*
X826194Y-484113D01*
X824666Y-483821D01*
X823138Y-484113D01*
X821173Y-485279D01*
X821828Y-477696D01*
X827723D01*
G01X741331Y-450196D02*
Y-432696D01*
X746571D01*
X748318Y-433571D01*
X749628Y-435613D01*
X750065Y-437946D01*
X749628Y-440279D01*
X748536Y-442029D01*
X746571Y-442905D01*
X741331D01*
G01X768001Y-434155D02*
X766691Y-433279D01*
X765163Y-432696D01*
X763416D01*
X761451Y-433571D01*
X759923Y-435029D01*
X758831Y-436780D01*
X757958Y-439696D01*
X757739Y-442321D01*
X758176Y-444946D01*
X758831Y-446696D01*
X760141Y-448446D01*
X761670Y-449613D01*
X763198Y-450196D01*
X764726D01*
X766255Y-449613D01*
X767565Y-448738D01*
X768657Y-447572D01*
G01X782444Y-440863D02*
X783318Y-439988D01*
X783973Y-438530D01*
X784410Y-436487D01*
X783973Y-434738D01*
X783100Y-433571D01*
X781571Y-432696D01*
X775676D01*
Y-450196D01*
X782881D01*
X784410Y-449030D01*
X785283Y-447279D01*
X785720Y-445238D01*
X785283Y-443196D01*
X783973Y-441446D01*
X782444Y-440863D01*
X775676D01*
G01X791648Y-456029D02*
X804748D01*
G01X810676Y-450196D02*
Y-432696D01*
X820720Y-450196D01*
Y-432696D01*
G01X833198Y-450196D02*
X831451Y-449904D01*
X829923Y-448738D01*
X828613Y-446988D01*
X827739Y-444946D01*
X827303Y-442613D01*
Y-440279D01*
X827739Y-437946D01*
X828613Y-435904D01*
X829923Y-434155D01*
X831451Y-432988D01*
X833198Y-432696D01*
X834944Y-432988D01*
X836473Y-434155D01*
X837783Y-435904D01*
X838657Y-437946D01*
X839093Y-440279D01*
Y-442613D01*
X838657Y-444946D01*
X837783Y-446988D01*
X836473Y-448738D01*
X834944Y-449904D01*
X833198Y-450196D01*
G01X884039Y-432696D02*
X889498Y-450196D01*
X894957Y-432696D01*
G01X911365Y-450196D02*
X902631D01*
Y-432696D01*
X911365D01*
G01X907871Y-441154D02*
X902631D01*
G01X920131Y-450196D02*
Y-432696D01*
X925590D01*
X927336Y-433571D01*
X928428Y-434738D01*
X928865Y-437071D01*
X928428Y-439405D01*
X927118Y-440863D01*
X925590Y-441738D01*
X920131D01*
G01X925590D02*
X928865Y-450196D01*
G01X941998Y-450779D02*
X941561Y-450488D01*
Y-449904D01*
X941998Y-449613D01*
X942435Y-449904D01*
Y-450488D01*
X941998Y-450779D01*
G01X915748Y-495196D02*
Y-477696D01*
X913128Y-481196D01*
G01Y-495196D02*
X918368D01*
G01X1082981Y-432696D02*
Y-450196D01*
X1091715D01*
G01X1108778D02*
Y-438530D01*
G01Y-440571D02*
X1107905Y-439405D01*
X1106594Y-438821D01*
X1105066Y-438530D01*
X1103538Y-439113D01*
X1102228Y-440279D01*
X1101354Y-442029D01*
X1100918Y-444363D01*
X1101354Y-446696D01*
X1102228Y-448446D01*
X1103538Y-449613D01*
X1105066Y-450196D01*
X1106594Y-449904D01*
X1107905Y-449030D01*
X1108778Y-447863D01*
G01X1117763Y-455446D02*
X1119073Y-456029D01*
X1120820Y-455446D01*
X1121911Y-454280D01*
X1122785Y-452821D01*
X1124094Y-448155D01*
X1126933Y-438530D01*
G01X1119946D02*
X1124094Y-448155D01*
G01X1136573Y-442321D02*
X1143560D01*
X1142905Y-440279D01*
X1141813Y-439113D01*
X1140285Y-438530D01*
X1138756Y-438821D01*
X1137446Y-439696D01*
X1136573Y-441738D01*
X1136136Y-443488D01*
Y-445238D01*
X1136573Y-446988D01*
X1137665Y-448738D01*
X1138975Y-449904D01*
X1140503Y-450196D01*
X1142031Y-449613D01*
X1143560Y-447863D01*
G01X1154291Y-450196D02*
Y-438530D01*
G01Y-440863D02*
X1155383Y-439696D01*
X1156475Y-438821D01*
X1158003Y-438530D01*
X1159094Y-438821D01*
X1160405Y-439696D01*
G01X1144215Y-477696D02*
Y-495196D01*
X1135481D01*
G01X1122348D02*
Y-477696D01*
X1124968Y-481196D01*
G01Y-495196D02*
X1119728D01*
G01X1104848Y-477696D02*
X1106595Y-478279D01*
X1107905Y-479738D01*
X1108778Y-481487D01*
X1109433Y-483821D01*
X1109651Y-486446D01*
X1109433Y-489071D01*
X1108778Y-491405D01*
X1107905Y-493155D01*
X1106595Y-494613D01*
X1104848Y-495196D01*
X1103102Y-494613D01*
X1101791Y-493155D01*
X1100918Y-491405D01*
X1100263Y-489071D01*
X1100045Y-486446D01*
X1100263Y-483821D01*
X1100918Y-481487D01*
X1101791Y-479738D01*
X1103102Y-478279D01*
X1104848Y-477696D01*
G01X1312898Y-495196D02*
X1311151Y-494904D01*
X1309623Y-493738D01*
X1308313Y-491988D01*
X1307439Y-489946D01*
X1307003Y-487613D01*
Y-485279D01*
X1307439Y-482946D01*
X1308313Y-480904D01*
X1309623Y-479155D01*
X1311151Y-477988D01*
X1312898Y-477696D01*
X1314644Y-477988D01*
X1316173Y-479155D01*
X1317483Y-480904D01*
X1318357Y-482946D01*
X1318793Y-485279D01*
Y-487613D01*
X1318357Y-489946D01*
X1317483Y-491988D01*
X1316173Y-493738D01*
X1314644Y-494904D01*
X1312898Y-495196D01*
G01X1314644Y-490529D02*
X1317265Y-495196D01*
G01X1325595Y-477696D02*
Y-490238D01*
X1326468Y-492863D01*
X1328215Y-494613D01*
X1330398Y-495196D01*
X1332581Y-494613D01*
X1334328Y-492863D01*
X1335201Y-490238D01*
Y-477696D01*
G01X1345278D02*
X1350518D01*
G01X1347898D02*
Y-495196D01*
G01X1345278D02*
X1350518D01*
G01X1360376D02*
Y-477696D01*
X1370420Y-495196D01*
Y-477696D01*
G01X1387701Y-479155D02*
X1386391Y-478279D01*
X1384863Y-477696D01*
X1383116D01*
X1381151Y-478571D01*
X1379623Y-480029D01*
X1378531Y-481780D01*
X1377658Y-484696D01*
X1377439Y-487321D01*
X1377876Y-489946D01*
X1378531Y-491696D01*
X1379841Y-493446D01*
X1381370Y-494613D01*
X1382898Y-495196D01*
X1384426D01*
X1385955Y-494613D01*
X1387265Y-493738D01*
X1388357Y-492572D01*
G01X1400398Y-495196D02*
Y-487321D01*
X1396031Y-477696D01*
G01X1404765D02*
X1400398Y-487321D01*
G01X1290595Y-450196D02*
Y-432696D01*
X1294961D01*
X1296708Y-433571D01*
X1298018Y-434738D01*
X1299110Y-436487D01*
X1299983Y-438530D01*
X1300201Y-441446D01*
X1299983Y-444363D01*
X1299110Y-446405D01*
X1298018Y-448155D01*
X1296708Y-449321D01*
X1294961Y-450196D01*
X1290595D01*
G01X1309623Y-442321D02*
X1316610D01*
X1315955Y-440279D01*
X1314863Y-439113D01*
X1313335Y-438530D01*
X1311806Y-438821D01*
X1310496Y-439696D01*
X1309623Y-441738D01*
X1309186Y-443488D01*
Y-445238D01*
X1309623Y-446988D01*
X1310715Y-448738D01*
X1312025Y-449904D01*
X1313553Y-450196D01*
X1315081Y-449613D01*
X1316610Y-447863D01*
G01X1327123Y-448155D02*
X1328215Y-449321D01*
X1329743Y-450196D01*
X1331053D01*
X1332363Y-449613D01*
X1333236Y-448738D01*
X1333673Y-447572D01*
X1333455Y-445821D01*
X1332581Y-444946D01*
X1328651Y-443196D01*
X1327778Y-441154D01*
X1328215Y-439696D01*
X1329088Y-438821D01*
X1330398Y-438530D01*
X1331708Y-438821D01*
X1333018Y-439696D01*
G01X1347898Y-438530D02*
Y-450196D01*
G01Y-433863D02*
X1347461Y-433571D01*
Y-432988D01*
X1347898Y-432696D01*
X1348335Y-432988D01*
Y-433571D01*
X1347898Y-433863D01*
G01X1362341Y-454571D02*
X1363870Y-455738D01*
X1365616Y-456029D01*
X1367144Y-455738D01*
X1368455Y-454280D01*
X1369328Y-452238D01*
Y-438530D01*
G01Y-440863D02*
X1368455Y-439696D01*
X1367144Y-438821D01*
X1365616Y-438530D01*
X1363870Y-439113D01*
X1362778Y-440279D01*
X1361904Y-442321D01*
X1361468Y-444363D01*
X1361686Y-446113D01*
X1362560Y-448155D01*
X1363870Y-449613D01*
X1365616Y-450196D01*
X1366926Y-449904D01*
X1368455Y-448738D01*
X1369328Y-447572D01*
G01X1379186Y-450196D02*
Y-438530D01*
G01Y-441446D02*
X1380060Y-439988D01*
X1381370Y-438821D01*
X1383116Y-438530D01*
X1384644Y-438821D01*
X1385955Y-439988D01*
X1386610Y-442029D01*
Y-450196D01*
G01X1397123Y-442321D02*
X1404110D01*
X1403455Y-440279D01*
X1402363Y-439113D01*
X1400835Y-438530D01*
X1399306Y-438821D01*
X1397996Y-439696D01*
X1397123Y-441738D01*
X1396686Y-443488D01*
Y-445238D01*
X1397123Y-446988D01*
X1398215Y-448738D01*
X1399525Y-449904D01*
X1401053Y-450196D01*
X1402581Y-449613D01*
X1404110Y-447863D01*
G01X1414841Y-450196D02*
Y-438530D01*
G01Y-440863D02*
X1415933Y-439696D01*
X1417025Y-438821D01*
X1418553Y-438530D01*
X1419644Y-438821D01*
X1420955Y-439696D01*
G01X1461598Y-477696D02*
X1459851Y-478279D01*
X1458541Y-479738D01*
X1457668Y-481487D01*
X1457013Y-483821D01*
X1456795Y-486446D01*
X1457013Y-489071D01*
X1457668Y-491405D01*
X1458541Y-493155D01*
X1459851Y-494613D01*
X1461598Y-495196D01*
X1463344Y-494613D01*
X1464655Y-493155D01*
X1465528Y-491405D01*
X1466183Y-489071D01*
X1466401Y-486446D01*
X1466183Y-483821D01*
X1465528Y-481487D01*
X1464655Y-479738D01*
X1463344Y-478279D01*
X1461598Y-477696D01*
G01X1474950Y-487905D02*
X1476478Y-485863D01*
X1477788Y-484696D01*
X1479535Y-484113D01*
X1481063Y-484696D01*
X1482155Y-485863D01*
X1483028Y-487613D01*
X1483246Y-489654D01*
X1483028Y-491405D01*
X1482155Y-493155D01*
X1480844Y-494613D01*
X1479316Y-495196D01*
X1477570Y-494613D01*
X1476041Y-492863D01*
X1475168Y-490238D01*
X1474950Y-487321D01*
X1475386Y-483530D01*
X1476041Y-481487D01*
X1477133Y-479446D01*
X1478661Y-477988D01*
X1480190Y-477696D01*
X1481718Y-478279D01*
X1482810Y-479738D01*
G01X1492668Y-495779D02*
X1500528Y-477696D01*
G01X1514098D02*
X1512351Y-478279D01*
X1511041Y-479738D01*
X1510168Y-481487D01*
X1509513Y-483821D01*
X1509295Y-486446D01*
X1509513Y-489071D01*
X1510168Y-491405D01*
X1511041Y-493155D01*
X1512351Y-494613D01*
X1514098Y-495196D01*
X1515844Y-494613D01*
X1517155Y-493155D01*
X1518028Y-491405D01*
X1518683Y-489071D01*
X1518901Y-486446D01*
X1518683Y-483821D01*
X1518028Y-481487D01*
X1517155Y-479738D01*
X1515844Y-478279D01*
X1514098Y-477696D01*
G01X1527886Y-493155D02*
X1529415Y-494613D01*
X1531161Y-495196D01*
X1532908Y-494613D01*
X1534436Y-492863D01*
X1535528Y-490238D01*
X1535965Y-487613D01*
Y-484405D01*
X1535528Y-481780D01*
X1534436Y-479446D01*
X1533126Y-478279D01*
X1531598Y-477696D01*
X1529851Y-478279D01*
X1528541Y-479446D01*
X1527668Y-481196D01*
X1527231Y-483530D01*
X1527668Y-485571D01*
X1528760Y-487613D01*
X1530070Y-488780D01*
X1531598Y-489071D01*
X1533344Y-488488D01*
X1534655Y-487029D01*
X1535965Y-484405D01*
G01X1545168Y-495779D02*
X1553028Y-477696D01*
G01X1562450Y-480613D02*
X1563760Y-478863D01*
X1565288Y-477988D01*
X1567035Y-477696D01*
X1569218Y-478279D01*
X1570746Y-479738D01*
X1571183Y-481487D01*
X1570965Y-483238D01*
X1570091Y-484696D01*
X1565725Y-487613D01*
X1563760Y-489654D01*
X1562450Y-492572D01*
X1562013Y-495196D01*
X1571183D01*
G01X1584098Y-477696D02*
X1582351Y-478279D01*
X1581041Y-479738D01*
X1580168Y-481487D01*
X1579513Y-483821D01*
X1579295Y-486446D01*
X1579513Y-489071D01*
X1580168Y-491405D01*
X1581041Y-493155D01*
X1582351Y-494613D01*
X1584098Y-495196D01*
X1585844Y-494613D01*
X1587155Y-493155D01*
X1588028Y-491405D01*
X1588683Y-489071D01*
X1588901Y-486446D01*
X1588683Y-483821D01*
X1588028Y-481487D01*
X1587155Y-479738D01*
X1585844Y-478279D01*
X1584098Y-477696D01*
G01X1601598Y-495196D02*
Y-477696D01*
X1598978Y-481196D01*
G01Y-495196D02*
X1604218D01*
G01X1618661D02*
X1619098Y-491405D01*
X1619753Y-488196D01*
X1620626Y-485279D01*
X1621718Y-482071D01*
X1623465Y-477696D01*
X1614731D01*
G01X1509295Y-450196D02*
Y-432696D01*
X1513661D01*
X1515408Y-433571D01*
X1516718Y-434738D01*
X1517810Y-436487D01*
X1518683Y-438530D01*
X1518901Y-441446D01*
X1518683Y-444363D01*
X1517810Y-446405D01*
X1516718Y-448155D01*
X1515408Y-449321D01*
X1513661Y-450196D01*
X1509295D01*
G01X1535528D02*
Y-438530D01*
G01Y-440571D02*
X1534655Y-439405D01*
X1533344Y-438821D01*
X1531816Y-438530D01*
X1530288Y-439113D01*
X1528978Y-440279D01*
X1528104Y-442029D01*
X1527668Y-444363D01*
X1528104Y-446696D01*
X1528978Y-448446D01*
X1530288Y-449613D01*
X1531816Y-450196D01*
X1533344Y-449904D01*
X1534655Y-449030D01*
X1535528Y-447863D01*
G01X1549098Y-432696D02*
Y-450196D01*
G01X1546041Y-438530D02*
X1552155D01*
G01X1563323Y-442321D02*
X1570310D01*
X1569655Y-440279D01*
X1568563Y-439113D01*
X1567035Y-438530D01*
X1565506Y-438821D01*
X1564196Y-439696D01*
X1563323Y-441738D01*
X1562886Y-443488D01*
Y-445238D01*
X1563323Y-446988D01*
X1564415Y-448738D01*
X1565725Y-449904D01*
X1567253Y-450196D01*
X1568781Y-449613D01*
X1570310Y-447863D01*
G54D19*
G01X724283Y860689D02*
X725283Y861689D01*
X737984D01*
M02*
